(lib_symbols
	(symbol "antmicroBatteryHoldersClipsContacts:BAT-HLD-012-SMT-TR"
			(exclude_from_sim no)
			(in_bom yes)
			(on_board yes)
			(property "Reference" "BT"
				(at 17.78 -5.08 0)
				(effects
					(font
						(size 1.27 1.27)
						(thickness 0.15)
					)
					(justify left bottom)
				)
			)
			(property "Value" "BAT-HLD-012-SMT-TR"
				(at 17.78 -10.16 0)
				(effects
					(font
						(size 1.27 1.27)
						(thickness 0.15)
					)
					(justify left bottom)
					(hide yes)
				)
			)
			(property "Footprint" "antmicro-footprints:BAT_BAT-HLD-012-SMT-TR"
				(at 17.78 -12.7 0)
				(effects
					(font
						(size 1.27 1.27)
						(thickness 0.15)
					)
					(justify left bottom)
					(hide yes)
				)
			)
			(property "Datasheet" "https://www.snapeda.com/parts/BAT-HLD-012-SMT-TR/Linx/datasheet/"
				(at 17.78 -15.24 0)
				(effects
					(font
						(size 1.27 1.27)
						(thickness 0.15)
					)
					(justify left bottom)
					(hide yes)
				)
			)
			(property "Description" "BATTERY HOLDER, CR1216/1225, SMT"
				(at 0 0 0)
				(effects
					(font
						(size 1.27 1.27)
					)
					(hide yes)
				)
			)
			(property "Manufacturer" "Linx Technologies"
				(at 17.78 -17.78 0)
				(effects
					(font
						(size 1.27 1.27)
						(thickness 0.15)
					)
					(justify left bottom)
					(hide yes)
				)
			)
			(property "MPN" "BAT-HLD-012-SMT-TR"
				(at 17.78 -7.62 0)
				(effects
					(font
						(size 1.27 1.27)
						(thickness 0.15)
					)
					(justify left bottom)
				)
			)
			(property "License" "Apache-2.0"
				(at 17.78 -20.32 0)
				(effects
					(font
						(size 1.27 1.27)
						(thickness 0.15)
					)
					(justify left bottom)
					(hide yes)
				)
			)
			(property "Author" "Antmicro"
				(at 17.78 -22.86 0)
				(effects
					(font
						(size 1.27 1.27)
						(thickness 0.15)
					)
					(justify left bottom)
					(hide yes)
				)
			)
			(property "ki_keywords" "HORIZONTAL, SMT, BATTERY, HOLDER"
				(at 0 0 0)
				(effects
					(font
						(size 1.27 1.27)
					)
					(hide yes)
				)
			)
			(symbol "BAT-HLD-012-SMT-TR_1_1"
				(polyline
					(pts
						(xy 0 -2.54) (xy 0 -3.81)
					)
					(stroke
						(width 0.254)
						(type default)
					)
					(fill
						(type background)
					)
				)
				(polyline
					(pts
						(xy 0 -4.445) (xy 0 -3.81)
					)
					(stroke
						(width 0.254)
						(type default)
					)
					(fill
						(type background)
					)
				)
				(polyline
					(pts
						(xy 0 -8.89) (xy 0 -8.255)
					)
					(stroke
						(width 0.254)
						(type default)
					)
					(fill
						(type background)
					)
				)
				(polyline
					(pts
						(xy 0 -8.89) (xy 0 -10.16)
					)
					(stroke
						(width 0.254)
						(type default)
					)
					(fill
						(type background)
					)
				)
				(polyline
					(pts
						(xy 1.27 -4.064) (xy 1.27 -3.048)
					)
					(stroke
						(width 0.254)
						(type default)
					)
					(fill
						(type background)
					)
				)
				(polyline
					(pts
						(xy 1.27 -5.715) (xy -1.27 -5.715)
					)
					(stroke
						(width 0.254)
						(type default)
					)
					(fill
						(type background)
					)
				)
				(polyline
					(pts
						(xy 1.27 -8.255) (xy -1.27 -8.255)
					)
					(stroke
						(width 0.254)
						(type default)
					)
					(fill
						(type background)
					)
				)
				(polyline
					(pts
						(xy 1.778 -3.556) (xy 0.762 -3.556)
					)
					(stroke
						(width 0.254)
						(type default)
					)
					(fill
						(type background)
					)
				)
				(polyline
					(pts
						(xy 2.54 -4.445) (xy -2.54 -4.445)
					)
					(stroke
						(width 0.254)
						(type default)
					)
					(fill
						(type background)
					)
				)
				(polyline
					(pts
						(xy 2.54 -6.985) (xy -2.54 -6.985)
					)
					(stroke
						(width 0.254)
						(type default)
					)
					(fill
						(type background)
					)
				)
				(pin power_out line
					(at 0 0 270)
					(length 2.54)
					(name "~"
						(effects
							(font
								(size 1.27 1.27)
							)
						)
					)
					(number "P1"
						(effects
							(font
								(size 1.27 1.27)
							)
						)
					)
				)
				(pin passive line
					(at 0 0 270)
					(length 2.54)
					(hide yes)
					(name "~"
						(effects
							(font
								(size 1.27 1.27)
							)
						)
					)
					(number "P2"
						(effects
							(font
								(size 1.27 1.27)
							)
						)
					)
				)
				(pin power_out line
					(at 0 -12.7 90)
					(length 2.54)
					(name "~"
						(effects
							(font
								(size 1.27 1.27)
							)
						)
					)
					(number "N"
						(effects
							(font
								(size 1.27 1.27)
							)
						)
					)
				)
			)
		)
	(symbol "antmicroCapacitors0402:C_100n_0402"
			(pin_numbers
				(hide yes)
			)
			(pin_names
				(hide yes)
			)
			(exclude_from_sim no)
			(in_bom yes)
			(on_board yes)
			(property "Reference" "C"
				(at 20.32 -5.08 0)
				(effects
					(font
						(size 1.27 1.27)
						(thickness 0.15)
					)
					(justify left bottom)
				)
			)
			(property "Value" "C_100n_0402"
				(at 20.32 -10.16 0)
				(effects
					(font
						(size 1.27 1.27)
						(thickness 0.15)
					)
					(justify left bottom)
					(hide yes)
				)
			)
			(property "Footprint" "antmicro-footprints:C_0402_1005Metric"
				(at 20.32 -12.7 0)
				(effects
					(font
						(size 1.27 1.27)
						(thickness 0.15)
					)
					(justify left bottom)
					(hide yes)
				)
			)
			(property "Datasheet" "https://www.murata.com/products/productdetail?partno=GRM155R61H104KE14%23"
				(at 20.32 -15.24 0)
				(effects
					(font
						(size 1.27 1.27)
						(thickness 0.15)
					)
					(justify left bottom)
					(hide yes)
				)
			)
			(property "Description" "SMD Multilayer Ceramic Capacitor, 0.1 µF, 50 V, 0402 [1005 Metric], ± 10%, X5R, GRM Series"
				(at 0 0 0)
				(effects
					(font
						(size 1.27 1.27)
					)
					(hide yes)
				)
			)
			(property "MPN" "GRM155R61H104KE14D"
				(at 20.32 -17.78 0)
				(effects
					(font
						(size 1.27 1.27)
						(thickness 0.15)
					)
					(justify left bottom)
					(hide yes)
				)
			)
			(property "Manufacturer" "Murata"
				(at 20.32 -20.32 0)
				(effects
					(font
						(size 1.27 1.27)
						(thickness 0.15)
					)
					(justify left bottom)
					(hide yes)
				)
			)
			(property "License" "Apache-2.0"
				(at 20.32 -22.86 0)
				(effects
					(font
						(size 1.27 1.27)
						(thickness 0.15)
					)
					(justify left bottom)
					(hide yes)
				)
			)
			(property "Author" "Antmicro"
				(at 20.32 -25.4 0)
				(effects
					(font
						(size 1.27 1.27)
						(thickness 0.15)
					)
					(justify left bottom)
					(hide yes)
				)
			)
			(property "Val" "100n"
				(at 20.32 -7.62 0)
				(effects
					(font
						(size 1.27 1.27)
						(thickness 0.15)
					)
					(justify left bottom)
				)
			)
			(property "Voltage" "50V"
				(at 20.32 -27.94 0)
				(effects
					(font
						(size 1.27 1.27)
					)
					(justify left bottom)
					(hide yes)
				)
			)
			(property "Dielectric" "X5R"
				(at 20.32 -30.48 0)
				(effects
					(font
						(size 1.27 1.27)
					)
					(justify left bottom)
					(hide yes)
				)
			)
			(property "ki_keywords" "0402, SMT, CAPACITOR, PASSIVE, CERAMIC, MLCC"
				(at 0 0 0)
				(effects
					(font
						(size 1.27 1.27)
					)
					(hide yes)
				)
			)
			(symbol "C_100n_0402_0_1"
				(polyline
					(pts
						(xy 2.032 -1.524) (xy 2.032 1.524)
					)
					(stroke
						(width 0.3048)
						(type default)
					)
					(fill
						(type none)
					)
				)
				(polyline
					(pts
						(xy 3.048 -1.524) (xy 3.048 1.524)
					)
					(stroke
						(width 0.3302)
						(type default)
					)
					(fill
						(type none)
					)
				)
			)
			(symbol "C_100n_0402_1_1"
				(pin passive line
					(at 0 0 0)
					(length 2.032)
					(name "~"
						(effects
							(font
								(size 1.27 1.27)
							)
						)
					)
					(number "1"
						(effects
							(font
								(size 1.27 1.27)
							)
						)
					)
				)
				(pin passive line
					(at 5.08 0 180)
					(length 2.032)
					(name "~"
						(effects
							(font
								(size 1.27 1.27)
							)
						)
					)
					(number "2"
						(effects
							(font
								(size 1.27 1.27)
							)
						)
					)
				)
			)
		)
	(symbol "antmicroCapacitors0402:C_10p_0402"
			(pin_numbers
				(hide yes)
			)
			(pin_names
				(hide yes)
			)
			(exclude_from_sim no)
			(in_bom yes)
			(on_board yes)
			(property "Reference" "C"
				(at 20.32 -5.08 0)
				(effects
					(font
						(size 1.27 1.27)
						(thickness 0.15)
					)
					(justify left bottom)
				)
			)
			(property "Value" "C_10p_0402"
				(at 20.32 -10.16 0)
				(effects
					(font
						(size 1.27 1.27)
						(thickness 0.15)
					)
					(justify left bottom)
					(hide yes)
				)
			)
			(property "Footprint" "antmicro-footprints:C_0402_1005Metric"
				(at 20.32 -12.7 0)
				(effects
					(font
						(size 1.27 1.27)
						(thickness 0.15)
					)
					(justify left bottom)
					(hide yes)
				)
			)
			(property "Datasheet" "https://www.murata.com/products/productdetail?partno=GCM1555C1H100GA16%23"
				(at 20.32 -15.24 0)
				(effects
					(font
						(size 1.27 1.27)
						(thickness 0.15)
					)
					(justify left bottom)
					(hide yes)
				)
			)
			(property "Description" "SMD Multilayer Ceramic Capacitor, 10 pF, 50 V, 0402 [1005 Metric], ± 2%, C0G / NP0, GCM"
				(at 0 0 0)
				(effects
					(font
						(size 1.27 1.27)
					)
					(hide yes)
				)
			)
			(property "MPN" "GCM1555C1H100GA16D"
				(at 20.32 -17.78 0)
				(effects
					(font
						(size 1.27 1.27)
						(thickness 0.15)
					)
					(justify left bottom)
					(hide yes)
				)
			)
			(property "Manufacturer" "Murata"
				(at 20.32 -20.32 0)
				(effects
					(font
						(size 1.27 1.27)
						(thickness 0.15)
					)
					(justify left bottom)
					(hide yes)
				)
			)
			(property "License" "Apache-2.0"
				(at 20.32 -22.86 0)
				(effects
					(font
						(size 1.27 1.27)
						(thickness 0.15)
					)
					(justify left bottom)
					(hide yes)
				)
			)
			(property "Author" "Antmicro"
				(at 20.32 -25.4 0)
				(effects
					(font
						(size 1.27 1.27)
						(thickness 0.15)
					)
					(justify left bottom)
					(hide yes)
				)
			)
			(property "Val" "10p"
				(at 20.32 -7.62 0)
				(effects
					(font
						(size 1.27 1.27)
						(thickness 0.15)
					)
					(justify left bottom)
				)
			)
			(property "Voltage" "50V"
				(at 20.32 -27.94 0)
				(effects
					(font
						(size 1.27 1.27)
					)
					(justify left bottom)
					(hide yes)
				)
			)
			(property "Dielectric" "C0G"
				(at 20.32 -30.48 0)
				(effects
					(font
						(size 1.27 1.27)
					)
					(justify left bottom)
					(hide yes)
				)
			)
			(property "ki_keywords" "0402, SMT, CAPACITOR, PASSIVE"
				(at 0 0 0)
				(effects
					(font
						(size 1.27 1.27)
					)
					(hide yes)
				)
			)
			(symbol "C_10p_0402_0_1"
				(polyline
					(pts
						(xy 2.032 -1.524) (xy 2.032 1.524)
					)
					(stroke
						(width 0.3048)
						(type default)
					)
					(fill
						(type none)
					)
				)
				(polyline
					(pts
						(xy 3.048 -1.524) (xy 3.048 1.524)
					)
					(stroke
						(width 0.3302)
						(type default)
					)
					(fill
						(type none)
					)
				)
			)
			(symbol "C_10p_0402_1_1"
				(pin passive line
					(at 0 0 0)
					(length 2.032)
					(name "~"
						(effects
							(font
								(size 1.27 1.27)
							)
						)
					)
					(number "1"
						(effects
							(font
								(size 1.27 1.27)
							)
						)
					)
				)
				(pin passive line
					(at 5.08 0 180)
					(length 2.032)
					(name "~"
						(effects
							(font
								(size 1.27 1.27)
							)
						)
					)
					(number "2"
						(effects
							(font
								(size 1.27 1.27)
							)
						)
					)
				)
			)
		)
	(symbol "antmicroCapacitors0402:C_16p_0402"
			(pin_numbers
				(hide yes)
			)
			(pin_names
				(hide yes)
			)
			(exclude_from_sim no)
			(in_bom yes)
			(on_board yes)
			(property "Reference" "C"
				(at 20.32 -5.08 0)
				(effects
					(font
						(size 1.27 1.27)
						(thickness 0.15)
					)
					(justify left bottom)
				)
			)
			(property "Value" "C_16p_0402"
				(at 20.32 -10.16 0)
				(effects
					(font
						(size 1.27 1.27)
						(thickness 0.15)
					)
					(justify left bottom)
					(hide yes)
				)
			)
			(property "Footprint" "antmicro-footprints:C_0402_1005Metric"
				(at 20.32 -12.7 0)
				(effects
					(font
						(size 1.27 1.27)
						(thickness 0.15)
					)
					(justify left bottom)
					(hide yes)
				)
			)
			(property "Datasheet" "https://www.passivecomponent.com/wp-content/uploads/datasheet/WTC_MLCC_General_Purpose.pdf"
				(at 20.32 -15.24 0)
				(effects
					(font
						(size 1.27 1.27)
						(thickness 0.15)
					)
					(justify left bottom)
					(hide yes)
				)
			)
			(property "Description" "SMD Multilayer Ceramic Capacitor, General Purpose, 16 pF, 50 V, 0402 [1005 Metric], ± 5%, C0G / NP0"
				(at 0 0 0)
				(effects
					(font
						(size 1.27 1.27)
					)
					(hide yes)
				)
			)
			(property "MPN" "0402N160J500CT"
				(at 20.32 -17.78 0)
				(effects
					(font
						(size 1.27 1.27)
						(thickness 0.15)
					)
					(justify left bottom)
					(hide yes)
				)
			)
			(property "Manufacturer" "Walsin"
				(at 20.32 -20.32 0)
				(effects
					(font
						(size 1.27 1.27)
						(thickness 0.15)
					)
					(justify left bottom)
					(hide yes)
				)
			)
			(property "License" "Apache-2.0"
				(at 20.32 -22.86 0)
				(effects
					(font
						(size 1.27 1.27)
						(thickness 0.15)
					)
					(justify left bottom)
					(hide yes)
				)
			)
			(property "Author" "Antmicro"
				(at 20.32 -25.4 0)
				(effects
					(font
						(size 1.27 1.27)
						(thickness 0.15)
					)
					(justify left bottom)
					(hide yes)
				)
			)
			(property "Val" "16p"
				(at 20.32 -7.62 0)
				(effects
					(font
						(size 1.27 1.27)
						(thickness 0.15)
					)
					(justify left bottom)
				)
			)
			(property "Voltage" ""
				(at 20.32 -27.94 0)
				(effects
					(font
						(size 1.27 1.27)
					)
					(justify left bottom)
					(hide yes)
				)
			)
			(property "Dielectric" ""
				(at 20.32 -30.48 0)
				(effects
					(font
						(size 1.27 1.27)
					)
					(justify left bottom)
					(hide yes)
				)
			)
			(property "ki_keywords" "0402, SMT, CAPACITOR, PASSIVE, MLCC"
				(at 0 0 0)
				(effects
					(font
						(size 1.27 1.27)
					)
					(hide yes)
				)
			)
			(symbol "C_16p_0402_0_1"
				(polyline
					(pts
						(xy 2.032 -1.524) (xy 2.032 1.524)
					)
					(stroke
						(width 0.3048)
						(type default)
					)
					(fill
						(type none)
					)
				)
				(polyline
					(pts
						(xy 3.048 -1.524) (xy 3.048 1.524)
					)
					(stroke
						(width 0.3302)
						(type default)
					)
					(fill
						(type none)
					)
				)
			)
			(symbol "C_16p_0402_1_1"
				(pin passive line
					(at 0 0 0)
					(length 2.032)
					(name "~"
						(effects
							(font
								(size 1.27 1.27)
							)
						)
					)
					(number "1"
						(effects
							(font
								(size 1.27 1.27)
							)
						)
					)
				)
				(pin passive line
					(at 5.08 0 180)
					(length 2.032)
					(name "~"
						(effects
							(font
								(size 1.27 1.27)
							)
						)
					)
					(number "2"
						(effects
							(font
								(size 1.27 1.27)
							)
						)
					)
				)
			)
		)
	(symbol "antmicroCapacitors0402:C_2u2_0402"
			(pin_numbers
				(hide yes)
			)
			(pin_names
				(hide yes)
			)
			(exclude_from_sim no)
			(in_bom yes)
			(on_board yes)
			(property "Reference" "C"
				(at 20.32 -5.08 0)
				(effects
					(font
						(size 1.27 1.27)
						(thickness 0.15)
					)
					(justify left bottom)
				)
			)
			(property "Value" "C_2u2_0402"
				(at 20.32 -10.16 0)
				(effects
					(font
						(size 1.27 1.27)
						(thickness 0.15)
					)
					(justify left bottom)
					(hide yes)
				)
			)
			(property "Footprint" "antmicro-footprints:C_0402_1005Metric"
				(at 20.32 -12.7 0)
				(effects
					(font
						(size 1.27 1.27)
						(thickness 0.15)
					)
					(justify left bottom)
					(hide yes)
				)
			)
			(property "Datasheet" "https://product.tdk.com/en/search/capacitor/ceramic/mlcc/info?part_no=C1005X5R1A225K050BC"
				(at 20.32 -15.24 0)
				(effects
					(font
						(size 1.27 1.27)
						(thickness 0.15)
					)
					(justify left bottom)
					(hide yes)
				)
			)
			(property "Description" "SMD Multilayer Ceramic Capacitor, 2.2 µF, 10 V, 0402 [1005 Metric], ± 10%, X5R, C"
				(at 0 0 0)
				(effects
					(font
						(size 1.27 1.27)
					)
					(hide yes)
				)
			)
			(property "MPN" "C1005X5R1A225K050BC"
				(at 20.32 -17.78 0)
				(effects
					(font
						(size 1.27 1.27)
						(thickness 0.15)
					)
					(justify left bottom)
					(hide yes)
				)
			)
			(property "Manufacturer" "TDK"
				(at 20.32 -20.32 0)
				(effects
					(font
						(size 1.27 1.27)
						(thickness 0.15)
					)
					(justify left bottom)
					(hide yes)
				)
			)
			(property "License" "Apache-2.0"
				(at 20.32 -22.86 0)
				(effects
					(font
						(size 1.27 1.27)
						(thickness 0.15)
					)
					(justify left bottom)
					(hide yes)
				)
			)
			(property "Author" "Antmicro"
				(at 20.32 -25.4 0)
				(effects
					(font
						(size 1.27 1.27)
						(thickness 0.15)
					)
					(justify left bottom)
					(hide yes)
				)
			)
			(property "Val" "2u2"
				(at 20.32 -7.62 0)
				(effects
					(font
						(size 1.27 1.27)
						(thickness 0.15)
					)
					(justify left bottom)
				)
			)
			(property "Voltage" ""
				(at 20.32 -27.94 0)
				(effects
					(font
						(size 1.27 1.27)
					)
					(justify left bottom)
					(hide yes)
				)
			)
			(property "Dielectric" ""
				(at 20.32 -30.48 0)
				(effects
					(font
						(size 1.27 1.27)
					)
					(justify left bottom)
					(hide yes)
				)
			)
			(property "ki_keywords" "0402, SMT, CAPACITOR, PASSIVE, CERAMIC, MLCC"
				(at 0 0 0)
				(effects
					(font
						(size 1.27 1.27)
					)
					(hide yes)
				)
			)
			(symbol "C_2u2_0402_0_1"
				(polyline
					(pts
						(xy 2.032 -1.524) (xy 2.032 1.524)
					)
					(stroke
						(width 0.3048)
						(type default)
					)
					(fill
						(type none)
					)
				)
				(polyline
					(pts
						(xy 3.048 -1.524) (xy 3.048 1.524)
					)
					(stroke
						(width 0.3302)
						(type default)
					)
					(fill
						(type none)
					)
				)
			)
			(symbol "C_2u2_0402_1_1"
				(pin passive line
					(at 0 0 0)
					(length 2.032)
					(name "~"
						(effects
							(font
								(size 1.27 1.27)
							)
						)
					)
					(number "1"
						(effects
							(font
								(size 1.27 1.27)
							)
						)
					)
				)
				(pin passive line
					(at 5.08 0 180)
					(length 2.032)
					(name "~"
						(effects
							(font
								(size 1.27 1.27)
							)
						)
					)
					(number "2"
						(effects
							(font
								(size 1.27 1.27)
							)
						)
					)
				)
			)
		)
	(symbol "antmicroCapacitors0402:C_4u7_0402"
			(pin_numbers
				(hide yes)
			)
			(pin_names
				(hide yes)
			)
			(exclude_from_sim no)
			(in_bom yes)
			(on_board yes)
			(property "Reference" "C"
				(at 20.32 -5.08 0)
				(effects
					(font
						(size 1.27 1.27)
						(thickness 0.15)
					)
					(justify left bottom)
				)
			)
			(property "Value" "C_4u7_0402"
				(at 20.32 -10.16 0)
				(effects
					(font
						(size 1.27 1.27)
						(thickness 0.15)
					)
					(justify left bottom)
					(hide yes)
				)
			)
			(property "Footprint" "antmicro-footprints:C_0402_1005Metric"
				(at 20.32 -12.7 0)
				(effects
					(font
						(size 1.27 1.27)
						(thickness 0.15)
					)
					(justify left bottom)
					(hide yes)
				)
			)
			(property "Datasheet" "https://www.murata.com/products/productdetail?partno=GRM155R61A475MEAA%23"
				(at 20.32 -15.24 0)
				(effects
					(font
						(size 1.27 1.27)
						(thickness 0.15)
					)
					(justify left bottom)
					(hide yes)
				)
			)
			(property "Description" "SMD Multilayer Ceramic Capacitor, 4.7 µF, 10 V, 0402 [1005 Metric], ± 20%, X5R, GRM Series"
				(at 0 0 0)
				(effects
					(font
						(size 1.27 1.27)
					)
					(hide yes)
				)
			)
			(property "MPN" "GRM155R61A475MEAAD"
				(at 20.32 -17.78 0)
				(effects
					(font
						(size 1.27 1.27)
						(thickness 0.15)
					)
					(justify left bottom)
					(hide yes)
				)
			)
			(property "Manufacturer" "Murata"
				(at 20.32 -20.32 0)
				(effects
					(font
						(size 1.27 1.27)
						(thickness 0.15)
					)
					(justify left bottom)
					(hide yes)
				)
			)
			(property "License" "Apache-2.0"
				(at 20.32 -22.86 0)
				(effects
					(font
						(size 1.27 1.27)
						(thickness 0.15)
					)
					(justify left bottom)
					(hide yes)
				)
			)
			(property "Author" "Antmicro"
				(at 20.32 -25.4 0)
				(effects
					(font
						(size 1.27 1.27)
						(thickness 0.15)
					)
					(justify left bottom)
					(hide yes)
				)
			)
			(property "Val" "4u7"
				(at 20.32 -7.62 0)
				(effects
					(font
						(size 1.27 1.27)
						(thickness 0.15)
					)
					(justify left bottom)
				)
			)
			(property "Voltage" ""
				(at 20.32 -27.94 0)
				(effects
					(font
						(size 1.27 1.27)
					)
					(justify left bottom)
					(hide yes)
				)
			)
			(property "Dielectric" ""
				(at 20.32 -30.48 0)
				(effects
					(font
						(size 1.27 1.27)
					)
					(justify left bottom)
					(hide yes)
				)
			)
			(property "ki_keywords" "0402, SMT, CAPACITOR, PASSIVE"
				(at 0 0 0)
				(effects
					(font
						(size 1.27 1.27)
					)
					(hide yes)
				)
			)
			(symbol "C_4u7_0402_0_1"
				(polyline
					(pts
						(xy 2.032 -1.524) (xy 2.032 1.524)
					)
					(stroke
						(width 0.3048)
						(type default)
					)
					(fill
						(type none)
					)
				)
				(polyline
					(pts
						(xy 3.048 -1.524) (xy 3.048 1.524)
					)
					(stroke
						(width 0.3302)
						(type default)
					)
					(fill
						(type none)
					)
				)
			)
			(symbol "C_4u7_0402_1_1"
				(pin passive line
					(at 0 0 0)
					(length 2.032)
					(name "~"
						(effects
							(font
								(size 1.27 1.27)
							)
						)
					)
					(number "1"
						(effects
							(font
								(size 1.27 1.27)
							)
						)
					)
				)
				(pin passive line
					(at 5.08 0 180)
					(length 2.032)
					(name "~"
						(effects
							(font
								(size 1.27 1.27)
							)
						)
					)
					(number "2"
						(effects
							(font
								(size 1.27 1.27)
							)
						)
					)
				)
			)
		)
	(symbol "antmicroFerriteBeadsandChips:FB_120Z_2A_Murata-BLM18PG_0603"
			(pin_numbers
				(hide yes)
			)
			(pin_names
				(hide yes)
			)
			(exclude_from_sim no)
			(in_bom yes)
			(on_board yes)
			(property "Reference" "FB"
				(at 15.24 0 0)
				(effects
					(font
						(size 1.27 1.27)
						(thickness 0.15)
					)
					(justify left bottom)
				)
			)
			(property "Value" "FB_120Z_2A_Murata-BLM18PG_0603"
				(at 15.24 -2.54 0)
				(effects
					(font
						(size 1.27 1.27)
						(thickness 0.15)
					)
					(justify left bottom)
					(hide yes)
				)
			)
			(property "Footprint" "antmicro-footprints:FB_0603_1608Metric"
				(at 15.24 -7.62 0)
				(effects
					(font
						(size 1.27 1.27)
						(thickness 0.15)
					)
					(justify left bottom)
					(hide yes)
				)
			)
			(property "Datasheet" "https://www.murata.com/en-us/products/productdata/8796738650142/ENFA0003.pdf"
				(at 15.24 -10.16 0)
				(effects
					(font
						(size 1.27 1.27)
						(thickness 0.15)
					)
					(justify left bottom)
					(hide yes)
				)
			)
			(property "Description" "Ferrite Bead, 0603 [1608 Metric], 120 ohm, 2 A, BLM18P, 0.05 ohm, ± 25%, DC power line"
				(at 0 0 0)
				(effects
					(font
						(size 1.27 1.27)
					)
					(hide yes)
				)
			)
			(property "Val" "120Z/2A"
				(at 15.24 -5.08 0)
				(effects
					(font
						(size 1.27 1.27)
					)
					(justify left bottom)
				)
			)
			(property "MPN" "BLM18PG121SN1D"
				(at 15.24 -12.7 0)
				(effects
					(font
						(size 1.27 1.27)
						(thickness 0.15)
					)
					(justify left bottom)
					(hide yes)
				)
			)
			(property "Manufacturer" "Murata"
				(at 15.24 -15.24 0)
				(effects
					(font
						(size 1.27 1.27)
						(thickness 0.15)
					)
					(justify left bottom)
					(hide yes)
				)
			)
			(property "Current" ""
				(at 20.32 -22.86 0)
				(effects
					(font
						(size 1.27 1.27)
						(thickness 0.15)
					)
					(justify left bottom)
					(hide yes)
				)
			)
			(property "Author" "Antmicro"
				(at 15.24 -17.78 0)
				(effects
					(font
						(size 1.27 1.27)
						(thickness 0.15)
					)
					(justify left bottom)
					(hide yes)
				)
			)
			(property "License" "Apache-2.0"
				(at 15.24 -20.32 0)
				(effects
					(font
						(size 1.27 1.27)
						(thickness 0.15)
					)
					(justify left bottom)
					(hide yes)
				)
			)
			(property "ki_keywords" "0603, SMT, FERRITE BEAD, PASSIVE"
				(at 0 0 0)
				(effects
					(font
						(size 1.27 1.27)
					)
					(hide yes)
				)
			)
			(symbol "FB_120Z_2A_Murata-BLM18PG_0603_0_1"
				(polyline
					(pts
						(xy 1.651 0) (xy 1.2446 0)
					)
					(stroke
						(width 0)
						(type default)
					)
					(fill
						(type none)
					)
				)
				(polyline
					(pts
						(xy 2.2606 -1.8288) (xy 1.0414 -1.1176) (xy 2.7432 1.8288) (xy 3.9624 1.1176) (xy 2.2606 -1.8288)
					)
					(stroke
						(width 0)
						(type default)
					)
					(fill
						(type none)
					)
				)
				(polyline
					(pts
						(xy 3.81 0) (xy 3.3274 0)
					)
					(stroke
						(width 0)
						(type default)
					)
					(fill
						(type none)
					)
				)
			)
			(symbol "FB_120Z_2A_Murata-BLM18PG_0603_1_1"
				(pin passive line
					(at 0 0 0)
					(length 1.27)
					(name "~"
						(effects
							(font
								(size 1.27 1.27)
							)
						)
					)
					(number "1"
						(effects
							(font
								(size 1.27 1.27)
							)
						)
					)
				)
				(pin passive line
					(at 5.08 0 180)
					(length 1.27)
					(name "~"
						(effects
							(font
								(size 1.27 1.27)
							)
						)
					)
					(number "2"
						(effects
							(font
								(size 1.27 1.27)
							)
						)
					)
				)
			)
		)
	(symbol "antmicroHumidityMoistureSensors:BME280"
			(exclude_from_sim no)
			(in_bom yes)
			(on_board yes)
			(property "Reference" "U"
				(at 33.02 -5.08 0)
				(effects
					(font
						(size 1.27 1.27)
						(thickness 0.15)
					)
					(justify left bottom)
				)
			)
			(property "Value" "BME280"
				(at 33.02 -7.62 0)
				(effects
					(font
						(size 1.27 1.27)
						(thickness 0.15)
					)
					(justify left bottom)
					(hide yes)
				)
			)
			(property "Footprint" "antmicro-footprints:LGA-8_2.5x2.5mm_BME280"
				(at 33.02 -10.16 0)
				(effects
					(font
						(size 1.27 1.27)
						(thickness 0.15)
					)
					(justify left bottom)
					(hide yes)
				)
			)
			(property "Datasheet" "https://www.bosch-sensortec.com/media/boschsensortec/downloads/datasheets/bst-bme280-ds002.pdf"
				(at 33.02 -12.7 0)
				(effects
					(font
						(size 1.27 1.27)
						(thickness 0.15)
					)
					(justify left bottom)
					(hide yes)
				)
			)
			(property "Description" "Sensor"
				(at 0 0 0)
				(effects
					(font
						(size 1.27 1.27)
					)
					(hide yes)
				)
			)
			(property "MPN" "BME280"
				(at 33.02 -15.24 0)
				(effects
					(font
						(size 1.27 1.27)
						(thickness 0.15)
					)
					(justify left bottom)
				)
			)
			(property "Manufacturer" "Bosch"
				(at 33.02 -17.78 0)
				(effects
					(font
						(size 1.27 1.27)
						(thickness 0.15)
					)
					(justify left bottom)
					(hide yes)
				)
			)
			(property "Author" "Antmicro"
				(at 33.02 -20.32 0)
				(effects
					(font
						(size 1.27 1.27)
						(thickness 0.15)
					)
					(justify left bottom)
					(hide yes)
				)
			)
			(property "License" "Apache-2.0"
				(at 33.02 -22.86 0)
				(effects
					(font
						(size 1.27 1.27)
						(thickness 0.15)
					)
					(justify left bottom)
					(hide yes)
				)
			)
			(property "ki_keywords" "SMT, SENSOR, IC"
				(at 0 0 0)
				(effects
					(font
						(size 1.27 1.27)
					)
					(hide yes)
				)
			)
			(symbol "BME280_1_1"
				(rectangle
					(start 17.78 -2.54)
					(end 2.54 -15.24)
					(stroke
						(width 0.254)
						(type default)
					)
					(fill
						(type background)
					)
				)
				(pin input line
					(at 0 -5.08 0)
					(length 2.54)
					(name "SCK"
						(effects
							(font
								(size 1.27 1.27)
							)
						)
					)
					(number "4"
						(effects
							(font
								(size 1.27 1.27)
							)
						)
					)
				)
				(pin bidirectional line
					(at 0 -7.62 0)
					(length 2.54)
					(name "SDI"
						(effects
							(font
								(size 1.27 1.27)
							)
						)
					)
					(number "3"
						(effects
							(font
								(size 1.27 1.27)
							)
						)
					)
				)
				(pin bidirectional line
					(at 0 -10.16 0)
					(length 2.54)
					(name "SDO"
						(effects
							(font
								(size 1.27 1.27)
							)
						)
					)
					(number "5"
						(effects
							(font
								(size 1.27 1.27)
							)
						)
					)
				)
				(pin input line
					(at 0 -12.7 0)
					(length 2.54)
					(name "CSB"
						(effects
							(font
								(size 1.27 1.27)
							)
						)
					)
					(number "2"
						(effects
							(font
								(size 1.27 1.27)
							)
						)
					)
				)
				(pin power_in line
					(at 10.16 0 270)
					(length 2.54)
					(name "VDDIO"
						(effects
							(font
								(size 1.27 1.27)
							)
						)
					)
					(number "6"
						(effects
							(font
								(size 1.27 1.27)
							)
						)
					)
				)
				(pin power_in line
					(at 10.16 -17.78 90)
					(length 2.54)
					(name "GND"
						(effects
							(font
								(size 1.27 1.27)
							)
						)
					)
					(number "1"
						(effects
							(font
								(size 1.27 1.27)
							)
						)
					)
				)
				(pin passive line
					(at 10.16 -17.78 90)
					(length 2.54)
					(hide yes)
					(name "GND"
						(effects
							(font
								(size 1.27 1.27)
							)
						)
					)
					(number "7"
						(effects
							(font
								(size 1.27 1.27)
							)
						)
					)
				)
				(pin power_in line
					(at 12.7 0 270)
					(length 2.54)
					(name "VDD"
						(effects
							(font
								(size 1.27 1.27)
							)
						)
					)
					(number "8"
						(effects
							(font
								(size 1.27 1.27)
							)
						)
					)
				)
			)
		)
	(symbol "antmicroHumidityMoistureSensors:SHT45"
			(exclude_from_sim no)
			(in_bom yes)
			(on_board yes)
			(property "Reference" "U"
				(at 27.94 -5.08 0)
				(effects
					(font
						(size 1.27 1.27)
						(thickness 0.15)
					)
					(justify left bottom)
				)
			)
			(property "Value" "SHT45"
				(at 27.94 -7.62 0)
				(effects
					(font
						(size 1.27 1.27)
						(thickness 0.15)
					)
					(justify left bottom)
					(hide yes)
				)
			)
			(property "Footprint" "antmicro-footprints:Sensirion_DFN-4-1.5x1.5x0.5mm_P0.8mm"
				(at 27.94 -10.16 0)
				(effects
					(font
						(size 1.27 1.27)
						(thickness 0.15)
					)
					(justify left bottom)
					(hide yes)
				)
			)
			(property "Datasheet" "https://sensirion.com/products/catalog/SHT45/"
				(at 27.94 -12.7 0)
				(effects
					(font
						(size 1.27 1.27)
						(thickness 0.15)
					)
					(justify left bottom)
					(hide yes)
				)
			)
			(property "Description" "Sensor"
				(at 0 0 0)
				(effects
					(font
						(size 1.27 1.27)
					)
					(hide yes)
				)
			)
			(property "Manufacturer" "Sensirion"
				(at 27.94 -15.24 0)
				(effects
					(font
						(size 1.27 1.27)
						(thickness 0.15)
					)
					(justify left bottom)
					(hide yes)
				)
			)
			(property "MPN" "SHT45-AD1B-R2"
				(at 27.94 -17.78 0)
				(effects
					(font
						(size 1.27 1.27)
						(thickness 0.15)
					)
					(justify left bottom)
				)
			)
			(property "Author" "Antmicro"
				(at 27.94 -20.32 0)
				(effects
					(font
						(size 1.27 1.27)
						(thickness 0.15)
					)
					(justify left bottom)
					(hide yes)
				)
			)
			(property "License" "Apache-2.0"
				(at 27.94 -22.86 0)
				(effects
					(font
						(size 1.27 1.27)
						(thickness 0.15)
					)
					(justify left bottom)
					(hide yes)
				)
			)
			(property "ki_keywords" "SMT, SENSOR, IC"
				(at 0 0 0)
				(effects
					(font
						(size 1.27 1.27)
					)
					(hide yes)
				)
			)
			(property "ki_fp_filters" "Sensirion*DFN*4*1.5x1.5mm"
				(at 0 0 0)
				(effects
					(font
						(size 1.27 1.27)
					)
					(hide yes)
				)
			)
			(symbol "SHT45_1_1"
				(rectangle
					(start 2.54 -2.54)
					(end 12.7 -12.7)
					(stroke
						(width 0.254)
						(type default)
					)
					(fill
						(type background)
					)
				)
				(pin bidirectional line
					(at 0 -5.08 0)
					(length 2.54)
					(name "SDA"
						(effects
							(font
								(size 1.27 1.27)
							)
						)
					)
					(number "1"
						(effects
							(font
								(size 1.27 1.27)
							)
						)
					)
				)
				(pin input line
					(at 0 -10.16 0)
					(length 2.54)
					(name "SCL"
						(effects
							(font
								(size 1.27 1.27)
							)
						)
					)
					(number "2"
						(effects
							(font
								(size 1.27 1.27)
							)
						)
					)
				)
				(pin power_in line
					(at 10.16 0 270)
					(length 2.54)
					(name "VDD"
						(effects
							(font
								(size 1.27 1.27)
							)
						)
					)
					(number "3"
						(effects
							(font
								(size 1.27 1.27)
							)
						)
					)
				)
				(pin power_in line
					(at 10.16 -15.24 90)
					(length 2.54)
					(name "VSS"
						(effects
							(font
								(size 1.27 1.27)
							)
						)
					)
					(number "4"
						(effects
							(font
								(size 1.27 1.27)
							)
						)
					)
				)
			)
		)
	(symbol "antmicroInterfaceControllers:FT232R_QFN"
			(exclude_from_sim no)
			(in_bom yes)
			(on_board yes)
			(property "Reference" "U"
				(at 40.64 -5.08 0)
				(effects
					(font
						(size 1.27 1.27)
						(thickness 0.15)
					)
					(justify left bottom)
				)
			)
			(property "Value" "FT232R_QFN"
				(at 40.64 -7.62 0)
				(effects
					(font
						(size 1.27 1.27)
						(thickness 0.15)
					)
					(justify left bottom)
					(hide yes)
				)
			)
			(property "Footprint" "antmicro-footprints:QFN-32-1EP_5x5mm"
				(at 40.64 -10.16 0)
				(effects
					(font
						(size 1.27 1.27)
						(thickness 0.15)
					)
					(justify left bottom)
					(hide yes)
				)
			)
			(property "Datasheet" "https://www.ftdichip.com/Support/Documents/DataSheets/ICs/DS_FT232R.pdf"
				(at 40.64 -12.7 0)
				(effects
					(font
						(size 1.27 1.27)
						(thickness 0.15)
					)
					(justify left bottom)
					(hide yes)
				)
			)
			(property "Description" "Interface Bridges, USB to UART, 1.8 V, 5.25 V, QFN, 32 Pins, -40 °C"
				(at 0 0 0)
				(effects
					(font
						(size 1.27 1.27)
					)
					(hide yes)
				)
			)
			(property "Manufacturer" "FTDI Chip"
				(at 40.64 -15.24 0)
				(effects
					(font
						(size 1.27 1.27)
						(thickness 0.15)
					)
					(justify left bottom)
					(hide yes)
				)
			)
			(property "MPN" "FT232RQ-REEL"
				(at 40.64 -17.78 0)
				(effects
					(font
						(size 1.27 1.27)
						(thickness 0.15)
					)
					(justify left bottom)
				)
			)
			(property "Author" "Antmicro"
				(at 40.64 -20.32 0)
				(effects
					(font
						(size 1.27 1.27)
						(thickness 0.15)
					)
					(justify left bottom)
					(hide yes)
				)
			)
			(property "License" "Apache-2.0"
				(at 40.64 -22.86 0)
				(effects
					(font
						(size 1.27 1.27)
						(thickness 0.15)
					)
					(justify left bottom)
					(hide yes)
				)
			)
			(property "ki_keywords" "SMT, INTERFACE, IC, CONTROLLER, USB, UART, I2C"
				(at 0 0 0)
				(effects
					(font
						(size 1.27 1.27)
					)
					(hide yes)
				)
			)
			(symbol "FT232R_QFN_1_1"
				(rectangle
					(start 2.54 2.54)
					(end 22.86 -43.18)
					(stroke
						(width 0.254)
						(type default)
					)
					(fill
						(type background)
					)
				)
				(pin power_in line
					(at 0 0 0)
					(length 2.54)
					(name "VCC"
						(effects
							(font
								(size 1.27 1.27)
							)
						)
					)
					(number "19"
						(effects
							(font
								(size 1.27 1.27)
							)
						)
					)
				)
				(pin power_in line
					(at 0 -2.54 0)
					(length 2.54)
					(name "VCCIO"
						(effects
							(font
								(size 1.27 1.27)
							)
						)
					)
					(number "1"
						(effects
							(font
								(size 1.27 1.27)
							)
						)
					)
				)
				(pin input line
					(at 0 -5.08 0)
					(length 2.54)
					(name "RESET#"
						(effects
							(font
								(size 1.27 1.27)
							)
						)
					)
					(number "18"
						(effects
							(font
								(size 1.27 1.27)
							)
						)
					)
				)
				(pin bidirectional line
					(at 0 -10.16 0)
					(length 2.54)
					(name "USBDP"
						(effects
							(font
								(size 1.27 1.27)
							)
						)
					)
					(number "14"
						(effects
							(font
								(size 1.27 1.27)
							)
						)
					)
				)
				(pin bidirectional line
					(at 0 -12.7 0)
					(length 2.54)
					(name "USBDM"
						(effects
							(font
								(size 1.27 1.27)
							)
						)
					)
					(number "15"
						(effects
							(font
								(size 1.27 1.27)
							)
						)
					)
				)
				(pin input line
					(at 0 -27.94 0)
					(length 2.54)
					(name "OSCI"
						(effects
							(font
								(size 1.27 1.27)
							)
						)
					)
					(number "27"
						(effects
							(font
								(size 1.27 1.27)
							)
						)
					)
				)
				(pin output line
					(at 0 -30.48 0)
					(length 2.54)
					(name "OSCO"
						(effects
							(font
								(size 1.27 1.27)
							)
						)
					)
					(number "28"
						(effects
							(font
								(size 1.27 1.27)
							)
						)
					)
				)
				(pin input line
					(at 0 -33.02 0)
					(length 2.54)
					(name "TEST"
						(effects
							(font
								(size 1.27 1.27)
							)
						)
					)
					(number "26"
						(effects
							(font
								(size 1.27 1.27)
							)
						)
					)
				)
				(pin power_in line
					(at 0 -35.56 0)
					(length 2.54)
					(name "GND"
						(effects
							(font
								(size 1.27 1.27)
							)
						)
					)
					(number "17"
						(effects
							(font
								(size 1.27 1.27)
							)
						)
					)
				)
				(pin passive line
					(at 0 -35.56 0)
					(length 2.54)
					(hide yes)
					(name "GND"
						(effects
							(font
								(size 1.27 1.27)
							)
						)
					)
					(number "20"
						(effects
							(font
								(size 1.27 1.27)
							)
						)
					)
				)
				(pin passive line
					(at 0 -35.56 0)
					(length 2.54)
					(hide yes)
					(name "GND"
						(effects
							(font
								(size 1.27 1.27)
							)
						)
					)
					(number "4"
						(effects
							(font
								(size 1.27 1.27)
							)
						)
					)
				)
				(pin power_in line
					(at 0 -38.1 0)
					(length 2.54)
					(name "AGND"
						(effects
							(font
								(size 1.27 1.27)
							)
						)
					)
					(number "24"
						(effects
							(font
								(size 1.27 1.27)
							)
						)
					)
				)
				(pin passive line
					(at 0 -40.64 0)
					(length 2.54)
					(name "EP"
						(effects
							(font
								(size 1.27 1.27)
							)
						)
					)
					(number "33"
						(effects
							(font
								(size 1.27 1.27)
							)
						)
					)
				)
				(pin no_connect line
					(at 2.54 -17.78 0)
					(length 2.54)
					(hide yes)
					(name "NC"
						(effects
							(font
								(size 1.27 1.27)
							)
						)
					)
					(number "13"
						(effects
							(font
								(size 1.27 1.27)
							)
						)
					)
				)
				(pin no_connect line
					(at 2.54 -20.32 0)
					(length 2.54)
					(hide yes)
					(name "NC"
						(effects
							(font
								(size 1.27 1.27)
							)
						)
					)
					(number "23"
						(effects
							(font
								(size 1.27 1.27)
							)
						)
					)
				)
				(pin no_connect line
					(at 2.54 -22.86 0)
					(length 2.54)
					(hide yes)
					(name "NC"
						(effects
							(font
								(size 1.27 1.27)
							)
						)
					)
					(number "25"
						(effects
							(font
								(size 1.27 1.27)
							)
						)
					)
				)
				(pin no_connect line
					(at 2.54 -25.4 0)
					(length 2.54)
					(hide yes)
					(name "NC"
						(effects
							(font
								(size 1.27 1.27)
							)
						)
					)
					(number "29"
						(effects
							(font
								(size 1.27 1.27)
							)
						)
					)
				)
				(pin no_connect line
					(at 22.86 -38.1 180)
					(length 2.54)
					(hide yes)
					(name "NC"
						(effects
							(font
								(size 1.27 1.27)
							)
						)
					)
					(number "5"
						(effects
							(font
								(size 1.27 1.27)
							)
						)
					)
				)
				(pin no_connect line
					(at 22.86 -40.64 180)
					(length 2.54)
					(hide yes)
					(name "NC"
						(effects
							(font
								(size 1.27 1.27)
							)
						)
					)
					(number "12"
						(effects
							(font
								(size 1.27 1.27)
							)
						)
					)
				)
				(pin output line
					(at 25.4 0 180)
					(length 2.54)
					(name "3V3OUT"
						(effects
							(font
								(size 1.27 1.27)
							)
						)
					)
					(number "16"
						(effects
							(font
								(size 1.27 1.27)
							)
						)
					)
				)
				(pin output line
					(at 25.4 -2.54 180)
					(length 2.54)
					(name "TXD"
						(effects
							(font
								(size 1.27 1.27)
							)
						)
					)
					(number "30"
						(effects
							(font
								(size 1.27 1.27)
							)
						)
					)
				)
				(pin input line
					(at 25.4 -5.08 180)
					(length 2.54)
					(name "RXD"
						(effects
							(font
								(size 1.27 1.27)
							)
						)
					)
					(number "2"
						(effects
							(font
								(size 1.27 1.27)
							)
						)
					)
				)
				(pin output line
					(at 25.4 -7.62 180)
					(length 2.54)
					(name "DTR#"
						(effects
							(font
								(size 1.27 1.27)
							)
						)
					)
					(number "31"
						(effects
							(font
								(size 1.27 1.27)
							)
						)
					)
				)
				(pin output line
					(at 25.4 -10.16 180)
					(length 2.54)
					(name "RTS#"
						(effects
							(font
								(size 1.27 1.27)
							)
						)
					)
					(number "32"
						(effects
							(font
								(size 1.27 1.27)
							)
						)
					)
				)
				(pin input line
					(at 25.4 -15.24 180)
					(length 2.54)
					(name "DSR#"
						(effects
							(font
								(size 1.27 1.27)
							)
						)
					)
					(number "6"
						(effects
							(font
								(size 1.27 1.27)
							)
						)
					)
				)
				(pin input line
					(at 25.4 -17.78 180)
					(length 2.54)
					(name "DCD#"
						(effects
							(font
								(size 1.27 1.27)
							)
						)
					)
					(number "7"
						(effects
							(font
								(size 1.27 1.27)
							)
						)
					)
				)
				(pin input line
					(at 25.4 -20.32 180)
					(length 2.54)
					(name "CTS#"
						(effects
							(font
								(size 1.27 1.27)
							)
						)
					)
					(number "8"
						(effects
							(font
								(size 1.27 1.27)
							)
						)
					)
				)
				(pin input line
					(at 25.4 -22.86 180)
					(length 2.54)
					(name "RI#"
						(effects
							(font
								(size 1.27 1.27)
							)
						)
					)
					(number "3"
						(effects
							(font
								(size 1.27 1.27)
							)
						)
					)
				)
				(pin bidirectional line
					(at 25.4 -25.4 180)
					(length 2.54)
					(name "CBUS0"
						(effects
							(font
								(size 1.27 1.27)
							)
						)
					)
					(number "22"
						(effects
							(font
								(size 1.27 1.27)
							)
						)
					)
				)
				(pin bidirectional line
					(at 25.4 -27.94 180)
					(length 2.54)
					(name "CBUS1"
						(effects
							(font
								(size 1.27 1.27)
							)
						)
					)
					(number "21"
						(effects
							(font
								(size 1.27 1.27)
							)
						)
					)
				)
				(pin bidirectional line
					(at 25.4 -30.48 180)
					(length 2.54)
					(name "CBUS2"
						(effects
							(font
								(size 1.27 1.27)
							)
						)
					)
					(number "10"
						(effects
							(font
								(size 1.27 1.27)
							)
						)
					)
				)
				(pin bidirectional line
					(at 25.4 -33.02 180)
					(length 2.54)
					(name "CBUS3"
						(effects
							(font
								(size 1.27 1.27)
							)
						)
					)
					(number "11"
						(effects
							(font
								(size 1.27 1.27)
							)
						)
					)
				)
				(pin bidirectional line
					(at 25.4 -35.56 180)
					(length 2.54)
					(name "CBUS4"
						(effects
							(font
								(size 1.27 1.27)
							)
						)
					)
					(number "9"
						(effects
							(font
								(size 1.27 1.27)
							)
						)
					)
				)
			)
		)
	(symbol "antmicroLEDIndicationDiscrete:LED_G_0603_KP-1608ZGC"
			(pin_numbers
				(hide yes)
			)
			(pin_names
				(hide yes)
			)
			(exclude_from_sim no)
			(in_bom yes)
			(on_board yes)
			(property "Reference" "D"
				(at 20.32 -2.54 0)
				(effects
					(font
						(size 1.27 1.27)
						(thickness 0.15)
					)
					(justify left bottom)
				)
			)
			(property "Value" "LED_G_0603_KP-1608ZGC"
				(at 20.32 -7.62 0)
				(effects
					(font
						(size 1.27 1.27)
						(thickness 0.15)
					)
					(justify left bottom)
					(hide yes)
				)
			)
			(property "Footprint" "antmicro-footprints:LED_0603_1608Metric_G"
				(at 20.32 -10.16 0)
				(effects
					(font
						(size 1.27 1.27)
						(thickness 0.15)
					)
					(justify left bottom)
					(hide yes)
				)
			)
			(property "Datasheet" "https://www.kingbright.com/attachments/file/psearch/000/00/00/KP-1608ZGC(Ver.19B).pdf"
				(at 20.32 -12.7 0)
				(effects
					(font
						(size 1.27 1.27)
						(thickness 0.15)
					)
					(justify left bottom)
					(hide yes)
				)
			)
			(property "Description" "LED, Green, SMD, 0603, 20 mA, 3.3 V, 525 nm"
				(at 0 0 0)
				(effects
					(font
						(size 1.27 1.27)
					)
					(hide yes)
				)
			)
			(property "MPN" "KP-1608ZGC"
				(at 20.32 -15.24 0)
				(effects
					(font
						(size 1.27 1.27)
						(thickness 0.15)
					)
					(justify left bottom)
					(hide yes)
				)
			)
			(property "Manufacturer" "Kingbright"
				(at 20.32 -17.78 0)
				(effects
					(font
						(size 1.27 1.27)
						(thickness 0.15)
					)
					(justify left bottom)
					(hide yes)
				)
			)
			(property "Color" "Green"
				(at 20.32 -5.08 0)
				(effects
					(font
						(size 1.27 1.27)
					)
					(justify left bottom)
				)
			)
			(property "Author" "Antmicro"
				(at 20.32 -20.32 0)
				(effects
					(font
						(size 1.27 1.27)
						(thickness 0.15)
					)
					(justify left bottom)
					(hide yes)
				)
			)
			(property "License" "Apache-2.0"
				(at 20.32 -22.86 0)
				(effects
					(font
						(size 1.27 1.27)
						(thickness 0.15)
					)
					(justify left bottom)
					(hide yes)
				)
			)
			(property "ki_keywords" "SMT, DIODE, SEMICONDUCTOR, LED"
				(at 0 0 0)
				(effects
					(font
						(size 1.27 1.27)
					)
					(hide yes)
				)
			)
			(symbol "LED_G_0603_KP-1608ZGC_0_1"
				(polyline
					(pts
						(xy 1.905 0) (xy 0.635 0)
					)
					(stroke
						(width 0)
						(type default)
					)
					(fill
						(type none)
					)
				)
				(polyline
					(pts
						(xy 4.445 0) (xy 3.175 0)
					)
					(stroke
						(width 0)
						(type default)
					)
					(fill
						(type none)
					)
				)
			)
			(symbol "LED_G_0603_KP-1608ZGC_1_1"
				(polyline
					(pts
						(xy 1.143 2.286) (xy 1.143 1.778) (xy 1.143 2.286) (xy 1.651 2.286) (xy 1.143 2.286) (xy 2.159 1.27)
					)
					(stroke
						(width 0.254)
						(type default)
					)
					(fill
						(type none)
					)
				)
				(polyline
					(pts
						(xy 1.778 1.016) (xy 1.778 -1.016)
					)
					(stroke
						(width 0.254)
						(type default)
					)
					(fill
						(type none)
					)
				)
				(polyline
					(pts
						(xy 2.159 2.54) (xy 2.159 2.032) (xy 2.159 2.54) (xy 2.667 2.54) (xy 2.159 2.54) (xy 3.048 1.651)
					)
					(stroke
						(width 0.254)
						(type default)
					)
					(fill
						(type none)
					)
				)
				(polyline
					(pts
						(xy 3.302 1.016) (xy 3.302 -1.016) (xy 1.778 0) (xy 3.302 1.016)
					)
					(stroke
						(width 0.254)
						(type default)
					)
					(fill
						(type outline)
					)
				)
				(pin passive line
					(at 0 0 0)
					(length 0.635)
					(name "C"
						(effects
							(font
								(size 1.27 1.27)
							)
						)
					)
					(number "1"
						(effects
							(font
								(size 1.27 1.27)
							)
						)
					)
				)
				(pin passive line
					(at 5.08 0 180)
					(length 0.635)
					(name "A"
						(effects
							(font
								(size 1.27 1.27)
							)
						)
					)
					(number "2"
						(effects
							(font
								(size 1.27 1.27)
							)
						)
					)
				)
			)
		)
	(symbol "antmicroMechanicalParts:MP_Pad5.4mm_Drill2.7mm"
			(pin_names
				(hide yes)
			)
			(exclude_from_sim no)
			(in_bom no)
			(on_board yes)
			(property "Reference" "MP"
				(at 20.32 -2.54 0)
				(effects
					(font
						(size 1.27 1.27)
						(thickness 0.15)
					)
					(justify left bottom)
				)
			)
			(property "Value" "MP_Pad5.4mm_Drill2.7mm"
				(at 20.32 -5.08 0)
				(effects
					(font
						(size 1.27 1.27)
						(thickness 0.15)
					)
					(justify left bottom)
				)
			)
			(property "Footprint" "antmicro-footprints:MP_Pad5.4mm_Drill2.7mm"
				(at 20.32 -7.62 0)
				(effects
					(font
						(size 1.27 1.27)
						(thickness 0.15)
					)
					(justify left bottom)
					(hide yes)
				)
			)
			(property "Datasheet" ""
				(at 16.84 -15.57 0)
				(effects
					(font
						(size 1.27 1.27)
						(thickness 0.15)
					)
					(justify left bottom)
					(hide yes)
				)
			)
			(property "Description" "Mechanical part"
				(at 0 0 0)
				(effects
					(font
						(size 1.27 1.27)
					)
					(hide yes)
				)
			)
			(property "Author" "Antmicro"
				(at 20.32 -10.16 0)
				(effects
					(font
						(size 1.27 1.27)
						(thickness 0.15)
					)
					(justify left bottom)
					(hide yes)
				)
			)
			(property "License" "Apache-2.0"
				(at 20.32 -12.7 0)
				(effects
					(font
						(size 1.27 1.27)
						(thickness 0.15)
					)
					(justify left bottom)
					(hide yes)
				)
			)
			(property "ki_keywords" "MECHANICAL"
				(at 0 0 0)
				(effects
					(font
						(size 1.27 1.27)
					)
					(hide yes)
				)
			)
			(symbol "MP_Pad5.4mm_Drill2.7mm_1_1"
				(circle
					(center 5.08 0)
					(radius 1.27)
					(stroke
						(width 0.254)
						(type default)
					)
					(fill
						(type background)
					)
				)
				(circle
					(center 5.08 0)
					(radius 2.54)
					(stroke
						(width 0.254)
						(type default)
					)
					(fill
						(type background)
					)
				)
				(pin passive line
					(at 0 0 0)
					(length 2.54)
					(name "~"
						(effects
							(font
								(size 1.27 1.27)
							)
						)
					)
					(number "1"
						(effects
							(font
								(size 1.27 1.27)
							)
						)
					)
				)
			)
		)
	(symbol "antmicroMechanicalParts:antmicro_logo"
			(exclude_from_sim no)
			(in_bom no)
			(on_board yes)
			(property "Reference" "N"
				(at 15.24 -5.08 0)
				(effects
					(font
						(size 1.27 1.27)
						(thickness 0.15)
					)
					(justify left bottom)
				)
			)
			(property "Value" "antmicro_logo"
				(at 15.24 -7.62 0)
				(effects
					(font
						(size 1.27 1.27)
						(thickness 0.15)
					)
					(justify left bottom)
				)
			)
			(property "Footprint" "antmicro-footprints:antmicro-logo"
				(at 15.24 -10.16 0)
				(effects
					(font
						(size 1.27 1.27)
						(thickness 0.15)
					)
					(justify left bottom)
					(hide yes)
				)
			)
			(property "Datasheet" ""
				(at 15.24 -12.7 0)
				(effects
					(font
						(size 1.27 1.27)
						(thickness 0.15)
					)
					(justify left bottom)
					(hide yes)
				)
			)
			(property "Description" "Mechanical part"
				(at 0 0 0)
				(effects
					(font
						(size 1.27 1.27)
					)
					(hide yes)
				)
			)
			(property "MPN" ""
				(at 0 0 0)
				(effects
					(font
						(size 1.27 1.27)
					)
				)
			)
			(property "Manufacturer" ""
				(at 15.24 -20.32 0)
				(effects
					(font
						(size 1.27 1.27)
						(thickness 0.15)
					)
					(justify left bottom)
					(hide yes)
				)
			)
			(property "Author" "Antmicro"
				(at 15.24 -15.24 0)
				(effects
					(font
						(size 1.27 1.27)
						(thickness 0.15)
					)
					(justify left bottom)
					(hide yes)
				)
			)
			(property "License" "Apache-2.0"
				(at 15.24 -17.78 0)
				(effects
					(font
						(size 1.27 1.27)
						(thickness 0.15)
					)
					(justify left bottom)
					(hide yes)
				)
			)
			(symbol "antmicro_logo_1_1"
				(text "Logo"
					(at 0 0 0)
					(effects
						(font
							(size 1.27 1.27)
							(thickness 0.15)
						)
						(justify left bottom)
					)
				)
			)
		)
	(symbol "antmicroMechanicalParts:oshw_logo"
			(exclude_from_sim no)
			(in_bom no)
			(on_board yes)
			(property "Reference" "N"
				(at 15.24 -5.08 0)
				(effects
					(font
						(size 1.27 1.27)
						(thickness 0.15)
					)
					(justify left bottom)
				)
			)
			(property "Value" "oshw_logo"
				(at 15.24 -7.62 0)
				(effects
					(font
						(size 1.27 1.27)
						(thickness 0.15)
					)
					(justify left bottom)
				)
			)
			(property "Footprint" "antmicro-footprints:oshw-logo"
				(at 15.24 -10.16 0)
				(effects
					(font
						(size 1.27 1.27)
						(thickness 0.15)
					)
					(justify left bottom)
					(hide yes)
				)
			)
			(property "Datasheet" ""
				(at 15.24 -12.7 0)
				(effects
					(font
						(size 1.27 1.27)
						(thickness 0.15)
					)
					(justify left bottom)
					(hide yes)
				)
			)
			(property "Description" "Mechanical part"
				(at 0 0 0)
				(effects
					(font
						(size 1.27 1.27)
					)
					(hide yes)
				)
			)
			(property "Author" "Antmicro"
				(at 15.24 -15.24 0)
				(effects
					(font
						(size 1.27 1.27)
						(thickness 0.15)
					)
					(justify left bottom)
					(hide yes)
				)
			)
			(property "License" "Apache-2.0"
				(at 15.24 -17.78 0)
				(effects
					(font
						(size 1.27 1.27)
						(thickness 0.15)
					)
					(justify left bottom)
					(hide yes)
				)
			)
			(property "MPN" ""
				(at 0 0 0)
				(effects
					(font
						(size 1.27 1.27)
					)
				)
			)
			(property "Manufacturer" ""
				(at 15.24 -20.32 0)
				(effects
					(font
						(size 1.27 1.27)
						(thickness 0.15)
					)
					(justify left bottom)
					(hide yes)
				)
			)
			(symbol "oshw_logo_1_1"
				(text "Logo"
					(at 0 0 0)
					(effects
						(font
							(size 1.27 1.27)
							(thickness 0.15)
						)
						(justify left bottom)
					)
				)
			)
		)
	(symbol "antmicroMemory:MB85RC1MTPNF-G"
			(exclude_from_sim no)
			(in_bom yes)
			(on_board yes)
			(property "Reference" "U"
				(at 35.56 -5.08 0)
				(effects
					(font
						(size 1.27 1.27)
						(thickness 0.15)
					)
					(justify left bottom)
				)
			)
			(property "Value" "MB85RC1MTPNF-G"
				(at 35.56 -7.62 0)
				(effects
					(font
						(size 1.27 1.27)
						(thickness 0.15)
					)
					(justify left bottom)
					(hide yes)
				)
			)
			(property "Footprint" "antmicro-footprints:SOP-8_3.9x5.05mm_P1.27mm"
				(at 35.56 -10.16 0)
				(effects
					(font
						(size 1.27 1.27)
						(thickness 0.15)
					)
					(justify left bottom)
					(hide yes)
				)
			)
			(property "Datasheet" "https://www.fujitsu.com/jp/group/fsm/en/documents/products/feram/lineup/MB85RC1MT-DS501-00027-5v0-E.pdf"
				(at 35.56 -12.7 0)
				(effects
					(font
						(size 1.27 1.27)
						(thickness 0.15)
					)
					(justify left bottom)
					(hide yes)
				)
			)
			(property "Description" "FRAM (Ferroelectric RAM) Memory IC 1Mbit I²C 3.4 MHz 130 ns 8-SOP"
				(at 0 0 0)
				(effects
					(font
						(size 1.27 1.27)
					)
					(hide yes)
				)
			)
			(property "MPN" "MB85RC1MTPNF-G-JNERE1"
				(at 35.56 -15.24 0)
				(effects
					(font
						(size 1.27 1.27)
						(thickness 0.15)
					)
					(justify left bottom)
				)
			)
			(property "Manufacturer" "Fujitsu"
				(at 35.56 -17.78 0)
				(effects
					(font
						(size 1.27 1.27)
						(thickness 0.15)
					)
					(justify left bottom)
					(hide yes)
				)
			)
			(property "Author" "Antmicro"
				(at 35.56 -20.32 0)
				(effects
					(font
						(size 1.27 1.27)
						(thickness 0.15)
					)
					(justify left bottom)
					(hide yes)
				)
			)
			(property "License" "Apache-2.0"
				(at 35.56 -22.86 0)
				(effects
					(font
						(size 1.27 1.27)
						(thickness 0.15)
					)
					(justify left bottom)
					(hide yes)
				)
			)
			(property "ki_keywords" "SMT, MEMORY, IC, I2C"
				(at 0 0 0)
				(effects
					(font
						(size 1.27 1.27)
					)
					(hide yes)
				)
			)
			(symbol "MB85RC1MTPNF-G_1_1"
				(rectangle
					(start 2.54 -2.54)
					(end 17.78 -17.78)
					(stroke
						(width 0.254)
						(type default)
					)
					(fill
						(type background)
					)
				)
				(pin no_connect line
					(at 0 -5.08 0)
					(length 2.54)
					(hide yes)
					(name "NC"
						(effects
							(font
								(size 1.27 1.27)
							)
						)
					)
					(number "1"
						(effects
							(font
								(size 1.27 1.27)
							)
						)
					)
				)
				(pin input line
					(at 0 -7.62 0)
					(length 2.54)
					(name "A1"
						(effects
							(font
								(size 1.27 1.27)
							)
						)
					)
					(number "2"
						(effects
							(font
								(size 1.27 1.27)
							)
						)
					)
				)
				(pin input line
					(at 0 -10.16 0)
					(length 2.54)
					(name "A2"
						(effects
							(font
								(size 1.27 1.27)
							)
						)
					)
					(number "3"
						(effects
							(font
								(size 1.27 1.27)
							)
						)
					)
				)
				(pin input line
					(at 0 -15.24 0)
					(length 2.54)
					(name "WP"
						(effects
							(font
								(size 1.27 1.27)
							)
						)
					)
					(number "7"
						(effects
							(font
								(size 1.27 1.27)
							)
						)
					)
				)
				(pin power_in line
					(at 10.16 0 270)
					(length 2.54)
					(name "VDD"
						(effects
							(font
								(size 1.27 1.27)
							)
						)
					)
					(number "8"
						(effects
							(font
								(size 1.27 1.27)
							)
						)
					)
				)
				(pin power_in line
					(at 10.16 -20.32 90)
					(length 2.54)
					(name "VSS"
						(effects
							(font
								(size 1.27 1.27)
							)
						)
					)
					(number "4"
						(effects
							(font
								(size 1.27 1.27)
							)
						)
					)
				)
				(pin bidirectional line
					(at 20.32 -7.62 180)
					(length 2.54)
					(name "SDA"
						(effects
							(font
								(size 1.27 1.27)
							)
						)
					)
					(number "5"
						(effects
							(font
								(size 1.27 1.27)
							)
						)
					)
				)
				(pin input line
					(at 20.32 -12.7 180)
					(length 2.54)
					(name "SCL"
						(effects
							(font
								(size 1.27 1.27)
							)
						)
					)
					(number "6"
						(effects
							(font
								(size 1.27 1.27)
							)
						)
					)
				)
			)
		)
	(symbol "antmicroMicrocontrollers:STM32G474CET6"
			(exclude_from_sim no)
			(in_bom yes)
			(on_board yes)
			(property "Reference" "U"
				(at 58.42 -5.08 0)
				(effects
					(font
						(size 1.27 1.27)
						(thickness 0.15)
					)
					(justify left bottom)
				)
			)
			(property "Value" "STM32G474CET6"
				(at 58.42 -7.62 0)
				(effects
					(font
						(size 1.27 1.27)
						(thickness 0.15)
					)
					(justify left bottom)
					(hide yes)
				)
			)
			(property "Footprint" "antmicro-footprints:LQFP-48_7x7mm_P0.5mm"
				(at 58.42 -10.16 0)
				(effects
					(font
						(size 1.27 1.27)
						(thickness 0.15)
					)
					(justify left bottom)
					(hide yes)
				)
			)
			(property "Datasheet" "https://www.st.com/resource/en/datasheet/stm32g474ce.pdf"
				(at 58.42 -12.7 0)
				(effects
					(font
						(size 1.27 1.27)
						(thickness 0.15)
					)
					(justify left bottom)
					(hide yes)
				)
			)
			(property "Description" "ARM MCU, STM32 Family STM32G4 Series Microcontrollers, ARM Cortex-M4F, 32 bit, 170 MHz, 512 KB"
				(at 0 0 0)
				(effects
					(font
						(size 1.27 1.27)
					)
					(hide yes)
				)
			)
			(property "MPN" "STM32G474CET6"
				(at 58.42 -15.24 0)
				(effects
					(font
						(size 1.27 1.27)
						(thickness 0.15)
					)
					(justify left bottom)
				)
			)
			(property "Manufacturer" "STMicroelectronics"
				(at 58.42 -17.78 0)
				(effects
					(font
						(size 1.27 1.27)
						(thickness 0.15)
					)
					(justify left bottom)
					(hide yes)
				)
			)
			(property "License" "Apache-2.0"
				(at 58.42 -20.32 0)
				(effects
					(font
						(size 1.27 1.27)
						(thickness 0.15)
					)
					(justify left bottom)
					(hide yes)
				)
			)
			(property "Author" "Antmicro"
				(at 58.42 -22.86 0)
				(effects
					(font
						(size 1.27 1.27)
						(thickness 0.15)
					)
					(justify left bottom)
					(hide yes)
				)
			)
			(property "ki_keywords" "SMT, MICROCONTROLLER, IC, ARM"
				(at 0 0 0)
				(effects
					(font
						(size 1.27 1.27)
					)
					(hide yes)
				)
			)
			(symbol "STM32G474CET6_1_1"
				(rectangle
					(start 2.54 2.54)
					(end 30.48 -60.96)
					(stroke
						(width 0.254)
						(type default)
					)
					(fill
						(type background)
					)
				)
				(pin power_in line
					(at 0 0 0)
					(length 2.54)
					(name "VDD"
						(effects
							(font
								(size 1.27 1.27)
							)
						)
					)
					(number "24"
						(effects
							(font
								(size 1.27 1.27)
							)
						)
					)
				)
				(pin passive line
					(at 0 0 0)
					(length 2.54)
					(hide yes)
					(name "VDD"
						(effects
							(font
								(size 1.27 1.27)
							)
						)
					)
					(number "36"
						(effects
							(font
								(size 1.27 1.27)
							)
						)
					)
				)
				(pin passive line
					(at 0 0 0)
					(length 2.54)
					(hide yes)
					(name "VDD"
						(effects
							(font
								(size 1.27 1.27)
							)
						)
					)
					(number "48"
						(effects
							(font
								(size 1.27 1.27)
							)
						)
					)
				)
				(pin power_in line
					(at 0 -2.54 0)
					(length 2.54)
					(name "VDDA"
						(effects
							(font
								(size 1.27 1.27)
							)
						)
					)
					(number "21"
						(effects
							(font
								(size 1.27 1.27)
							)
						)
					)
				)
				(pin passive line
					(at 0 -5.08 0)
					(length 2.54)
					(name "VREF+"
						(effects
							(font
								(size 1.27 1.27)
							)
						)
					)
					(number "20"
						(effects
							(font
								(size 1.27 1.27)
							)
						)
					)
				)
				(pin power_in line
					(at 0 -7.62 0)
					(length 2.54)
					(name "VBAT"
						(effects
							(font
								(size 1.27 1.27)
							)
						)
					)
					(number "1"
						(effects
							(font
								(size 1.27 1.27)
							)
						)
					)
				)
				(pin bidirectional line
					(at 0 -11.43 0)
					(length 2.54)
					(name "PG10-NRST"
						(effects
							(font
								(size 1.27 1.27)
							)
						)
					)
					(number "7"
						(effects
							(font
								(size 1.27 1.27)
							)
						)
					)
				)
				(pin bidirectional line
					(at 0 -13.97 0)
					(length 2.54)
					(name "PA0"
						(effects
							(font
								(size 1.27 1.27)
							)
						)
					)
					(number "8"
						(effects
							(font
								(size 1.27 1.27)
							)
						)
					)
				)
				(pin bidirectional line
					(at 0 -16.51 0)
					(length 2.54)
					(name "PA1"
						(effects
							(font
								(size 1.27 1.27)
							)
						)
					)
					(number "9"
						(effects
							(font
								(size 1.27 1.27)
							)
						)
					)
				)
				(pin bidirectional line
					(at 0 -19.05 0)
					(length 2.54)
					(name "PA2"
						(effects
							(font
								(size 1.27 1.27)
							)
						)
					)
					(number "10"
						(effects
							(font
								(size 1.27 1.27)
							)
						)
					)
				)
				(pin bidirectional line
					(at 0 -21.59 0)
					(length 2.54)
					(name "PA3"
						(effects
							(font
								(size 1.27 1.27)
							)
						)
					)
					(number "11"
						(effects
							(font
								(size 1.27 1.27)
							)
						)
					)
				)
				(pin bidirectional line
					(at 0 -24.13 0)
					(length 2.54)
					(name "PA4"
						(effects
							(font
								(size 1.27 1.27)
							)
						)
					)
					(number "12"
						(effects
							(font
								(size 1.27 1.27)
							)
						)
					)
				)
				(pin bidirectional line
					(at 0 -26.67 0)
					(length 2.54)
					(name "PA5"
						(effects
							(font
								(size 1.27 1.27)
							)
						)
					)
					(number "13"
						(effects
							(font
								(size 1.27 1.27)
							)
						)
					)
				)
				(pin bidirectional line
					(at 0 -29.21 0)
					(length 2.54)
					(name "PA6"
						(effects
							(font
								(size 1.27 1.27)
							)
						)
					)
					(number "14"
						(effects
							(font
								(size 1.27 1.27)
							)
						)
					)
				)
				(pin bidirectional line
					(at 0 -31.75 0)
					(length 2.54)
					(name "PA7"
						(effects
							(font
								(size 1.27 1.27)
							)
						)
					)
					(number "15"
						(effects
							(font
								(size 1.27 1.27)
							)
						)
					)
				)
				(pin bidirectional line
					(at 0 -34.29 0)
					(length 2.54)
					(name "PA8"
						(effects
							(font
								(size 1.27 1.27)
							)
						)
					)
					(number "30"
						(effects
							(font
								(size 1.27 1.27)
							)
						)
					)
				)
				(pin bidirectional line
					(at 0 -36.83 0)
					(length 2.54)
					(name "PA9"
						(effects
							(font
								(size 1.27 1.27)
							)
						)
					)
					(number "31"
						(effects
							(font
								(size 1.27 1.27)
							)
						)
					)
				)
				(pin bidirectional line
					(at 0 -39.37 0)
					(length 2.54)
					(name "PA10"
						(effects
							(font
								(size 1.27 1.27)
							)
						)
					)
					(number "32"
						(effects
							(font
								(size 1.27 1.27)
							)
						)
					)
				)
				(pin bidirectional line
					(at 0 -41.91 0)
					(length 2.54)
					(name "PA11"
						(effects
							(font
								(size 1.27 1.27)
							)
						)
					)
					(number "33"
						(effects
							(font
								(size 1.27 1.27)
							)
						)
					)
				)
				(pin bidirectional line
					(at 0 -44.45 0)
					(length 2.54)
					(name "PA12"
						(effects
							(font
								(size 1.27 1.27)
							)
						)
					)
					(number "34"
						(effects
							(font
								(size 1.27 1.27)
							)
						)
					)
				)
				(pin bidirectional line
					(at 0 -46.99 0)
					(length 2.54)
					(name "PA13"
						(effects
							(font
								(size 1.27 1.27)
							)
						)
					)
					(number "37"
						(effects
							(font
								(size 1.27 1.27)
							)
						)
					)
				)
				(pin bidirectional line
					(at 0 -49.53 0)
					(length 2.54)
					(name "PA14"
						(effects
							(font
								(size 1.27 1.27)
							)
						)
					)
					(number "38"
						(effects
							(font
								(size 1.27 1.27)
							)
						)
					)
				)
				(pin bidirectional line
					(at 0 -52.07 0)
					(length 2.54)
					(name "PA15"
						(effects
							(font
								(size 1.27 1.27)
							)
						)
					)
					(number "39"
						(effects
							(font
								(size 1.27 1.27)
							)
						)
					)
				)
				(pin power_in line
					(at 0 -55.88 0)
					(length 2.54)
					(name "VSSA"
						(effects
							(font
								(size 1.27 1.27)
							)
						)
					)
					(number "19"
						(effects
							(font
								(size 1.27 1.27)
							)
						)
					)
				)
				(pin power_in line
					(at 0 -58.42 0)
					(length 2.54)
					(name "VSS"
						(effects
							(font
								(size 1.27 1.27)
							)
						)
					)
					(number "23"
						(effects
							(font
								(size 1.27 1.27)
							)
						)
					)
				)
				(pin passive line
					(at 0 -58.42 0)
					(length 2.54)
					(hide yes)
					(name "VSS"
						(effects
							(font
								(size 1.27 1.27)
							)
						)
					)
					(number "35"
						(effects
							(font
								(size 1.27 1.27)
							)
						)
					)
				)
				(pin passive line
					(at 0 -58.42 0)
					(length 2.54)
					(hide yes)
					(name "VSS"
						(effects
							(font
								(size 1.27 1.27)
							)
						)
					)
					(number "47"
						(effects
							(font
								(size 1.27 1.27)
							)
						)
					)
				)
				(pin bidirectional line
					(at 33.02 0 180)
					(length 2.54)
					(name "PC13"
						(effects
							(font
								(size 1.27 1.27)
							)
						)
					)
					(number "2"
						(effects
							(font
								(size 1.27 1.27)
							)
						)
					)
				)
				(pin bidirectional line
					(at 33.02 -2.54 180)
					(length 2.54)
					(name "PC14-OSC32_IN"
						(effects
							(font
								(size 1.27 1.27)
							)
						)
					)
					(number "3"
						(effects
							(font
								(size 1.27 1.27)
							)
						)
					)
				)
				(pin bidirectional line
					(at 33.02 -5.08 180)
					(length 2.54)
					(name "PC15-OSC32_OUT"
						(effects
							(font
								(size 1.27 1.27)
							)
						)
					)
					(number "4"
						(effects
							(font
								(size 1.27 1.27)
							)
						)
					)
				)
				(pin bidirectional line
					(at 33.02 -8.89 180)
					(length 2.54)
					(name "PB0"
						(effects
							(font
								(size 1.27 1.27)
							)
						)
					)
					(number "16"
						(effects
							(font
								(size 1.27 1.27)
							)
						)
					)
				)
				(pin bidirectional line
					(at 33.02 -11.43 180)
					(length 2.54)
					(name "PB1"
						(effects
							(font
								(size 1.27 1.27)
							)
						)
					)
					(number "17"
						(effects
							(font
								(size 1.27 1.27)
							)
						)
					)
				)
				(pin bidirectional line
					(at 33.02 -13.97 180)
					(length 2.54)
					(name "PB2"
						(effects
							(font
								(size 1.27 1.27)
							)
						)
					)
					(number "18"
						(effects
							(font
								(size 1.27 1.27)
							)
						)
					)
				)
				(pin bidirectional line
					(at 33.02 -16.51 180)
					(length 2.54)
					(name "PB3"
						(effects
							(font
								(size 1.27 1.27)
							)
						)
					)
					(number "40"
						(effects
							(font
								(size 1.27 1.27)
							)
						)
					)
				)
				(pin bidirectional line
					(at 33.02 -19.05 180)
					(length 2.54)
					(name "PB4"
						(effects
							(font
								(size 1.27 1.27)
							)
						)
					)
					(number "41"
						(effects
							(font
								(size 1.27 1.27)
							)
						)
					)
				)
				(pin bidirectional line
					(at 33.02 -21.59 180)
					(length 2.54)
					(name "PB5"
						(effects
							(font
								(size 1.27 1.27)
							)
						)
					)
					(number "42"
						(effects
							(font
								(size 1.27 1.27)
							)
						)
					)
				)
				(pin bidirectional line
					(at 33.02 -24.13 180)
					(length 2.54)
					(name "PB6"
						(effects
							(font
								(size 1.27 1.27)
							)
						)
					)
					(number "43"
						(effects
							(font
								(size 1.27 1.27)
							)
						)
					)
				)
				(pin bidirectional line
					(at 33.02 -26.67 180)
					(length 2.54)
					(name "PB7"
						(effects
							(font
								(size 1.27 1.27)
							)
						)
					)
					(number "44"
						(effects
							(font
								(size 1.27 1.27)
							)
						)
					)
				)
				(pin bidirectional line
					(at 33.02 -29.21 180)
					(length 2.54)
					(name "PB8-BOOT0"
						(effects
							(font
								(size 1.27 1.27)
							)
						)
					)
					(number "45"
						(effects
							(font
								(size 1.27 1.27)
							)
						)
					)
				)
				(pin bidirectional line
					(at 33.02 -31.75 180)
					(length 2.54)
					(name "PB9"
						(effects
							(font
								(size 1.27 1.27)
							)
						)
					)
					(number "46"
						(effects
							(font
								(size 1.27 1.27)
							)
						)
					)
				)
				(pin bidirectional line
					(at 33.02 -34.29 180)
					(length 2.54)
					(name "PB10"
						(effects
							(font
								(size 1.27 1.27)
							)
						)
					)
					(number "22"
						(effects
							(font
								(size 1.27 1.27)
							)
						)
					)
				)
				(pin bidirectional line
					(at 33.02 -36.83 180)
					(length 2.54)
					(name "PB11"
						(effects
							(font
								(size 1.27 1.27)
							)
						)
					)
					(number "25"
						(effects
							(font
								(size 1.27 1.27)
							)
						)
					)
				)
				(pin bidirectional line
					(at 33.02 -39.37 180)
					(length 2.54)
					(name "PB12"
						(effects
							(font
								(size 1.27 1.27)
							)
						)
					)
					(number "26"
						(effects
							(font
								(size 1.27 1.27)
							)
						)
					)
				)
				(pin bidirectional line
					(at 33.02 -41.91 180)
					(length 2.54)
					(name "PB13"
						(effects
							(font
								(size 1.27 1.27)
							)
						)
					)
					(number "27"
						(effects
							(font
								(size 1.27 1.27)
							)
						)
					)
				)
				(pin bidirectional line
					(at 33.02 -44.45 180)
					(length 2.54)
					(name "PB14"
						(effects
							(font
								(size 1.27 1.27)
							)
						)
					)
					(number "28"
						(effects
							(font
								(size 1.27 1.27)
							)
						)
					)
				)
				(pin bidirectional line
					(at 33.02 -46.99 180)
					(length 2.54)
					(name "PB15"
						(effects
							(font
								(size 1.27 1.27)
							)
						)
					)
					(number "29"
						(effects
							(font
								(size 1.27 1.27)
							)
						)
					)
				)
				(pin bidirectional line
					(at 33.02 -50.8 180)
					(length 2.54)
					(name "PF0-OSC_IN"
						(effects
							(font
								(size 1.27 1.27)
							)
						)
					)
					(number "5"
						(effects
							(font
								(size 1.27 1.27)
							)
						)
					)
				)
				(pin bidirectional line
					(at 33.02 -53.34 180)
					(length 2.54)
					(name "PF1-OSC_OUT"
						(effects
							(font
								(size 1.27 1.27)
							)
						)
					)
					(number "6"
						(effects
							(font
								(size 1.27 1.27)
							)
						)
					)
				)
			)
		)
	(symbol "antmicroPMICVoltageRegulatorsLinear:AP7370-33SA-7"
			(exclude_from_sim no)
			(in_bom yes)
			(on_board yes)
			(property "Reference" "U"
				(at 30.48 -5.08 0)
				(effects
					(font
						(size 1.27 1.27)
						(thickness 0.15)
					)
					(justify left bottom)
				)
			)
			(property "Value" "AP7370-33SA-7"
				(at 30.48 -7.62 0)
				(effects
					(font
						(size 1.27 1.27)
						(thickness 0.15)
					)
					(justify left bottom)
					(hide yes)
				)
			)
			(property "Footprint" "antmicro-footprints:SOT-23-3"
				(at 30.48 -10.16 0)
				(effects
					(font
						(size 1.27 1.27)
						(thickness 0.15)
					)
					(justify left bottom)
					(hide yes)
				)
			)
			(property "Datasheet" "https://www.diodes.com/assets/Datasheets/AP7370.pdf"
				(at 30.48 -12.7 0)
				(effects
					(font
						(size 1.27 1.27)
						(thickness 0.15)
					)
					(justify left bottom)
					(hide yes)
				)
			)
			(property "Description" "Voltage regulator"
				(at 0 0 0)
				(effects
					(font
						(size 1.27 1.27)
					)
					(hide yes)
				)
			)
			(property "MPN" "AP7370-33SA-7"
				(at 30.48 -15.24 0)
				(effects
					(font
						(size 1.27 1.27)
						(thickness 0.15)
					)
					(justify left bottom)
				)
			)
			(property "Manufacturer" "Diodes Incorporated"
				(at 30.48 -17.78 0)
				(effects
					(font
						(size 1.27 1.27)
						(thickness 0.15)
					)
					(justify left bottom)
					(hide yes)
				)
			)
			(property "Author" "Antmicro"
				(at 30.48 -20.32 0)
				(effects
					(font
						(size 1.27 1.27)
						(thickness 0.15)
					)
					(justify left bottom)
					(hide yes)
				)
			)
			(property "License" "Apache-2.0"
				(at 30.48 -22.86 0)
				(effects
					(font
						(size 1.27 1.27)
						(thickness 0.15)
					)
					(justify left bottom)
					(hide yes)
				)
			)
			(property "ki_keywords" "SMT, PMIC, IC, VOLTAGE, LDO"
				(at 0 0 0)
				(effects
					(font
						(size 1.27 1.27)
					)
					(hide yes)
				)
			)
			(symbol "AP7370-33SA-7_1_1"
				(rectangle
					(start 2.54 1.27)
					(end 12.7 -7.62)
					(stroke
						(width 0.254)
						(type default)
					)
					(fill
						(type background)
					)
				)
				(pin power_in line
					(at 0 0 0)
					(length 2.54)
					(name "VIN"
						(effects
							(font
								(size 1.27 1.27)
							)
						)
					)
					(number "3"
						(effects
							(font
								(size 1.27 1.27)
							)
						)
					)
				)
				(pin power_in line
					(at 7.62 -10.16 90)
					(length 2.54)
					(name "GND"
						(effects
							(font
								(size 1.27 1.27)
							)
						)
					)
					(number "1"
						(effects
							(font
								(size 1.27 1.27)
							)
						)
					)
				)
				(pin power_out line
					(at 15.24 0 180)
					(length 2.54)
					(name "VOUT"
						(effects
							(font
								(size 1.27 1.27)
							)
						)
					)
					(number "2"
						(effects
							(font
								(size 1.27 1.27)
							)
						)
					)
				)
			)
		)
	(symbol "antmicroResistors0402:R_0R_0402"
			(pin_numbers
				(hide yes)
			)
			(pin_names
				(hide yes)
			)
			(exclude_from_sim no)
			(in_bom yes)
			(on_board yes)
			(property "Reference" "R"
				(at 20.32 -5.08 0)
				(effects
					(font
						(size 1.27 1.27)
						(thickness 0.15)
					)
					(justify left bottom)
				)
			)
			(property "Value" "R_0R_0402"
				(at 20.32 -12.7 0)
				(effects
					(font
						(size 1.27 1.27)
						(thickness 0.15)
					)
					(justify left bottom)
					(hide yes)
				)
			)
			(property "Footprint" "antmicro-footprints:R_0402_1005Metric"
				(at 20.32 -15.24 0)
				(effects
					(font
						(size 1.27 1.27)
						(thickness 0.15)
					)
					(justify left bottom)
					(hide yes)
				)
			)
			(property "Datasheet" "https://industrial.panasonic.com/cdbs/www-data/pdf/RDA0000/AOA0000C301.pdf"
				(at 20.32 -17.78 0)
				(effects
					(font
						(size 1.27 1.27)
						(thickness 0.15)
					)
					(justify left bottom)
					(hide yes)
				)
			)
			(property "Description" "SMD Chip Resistor, Jumper, 0 ohm, 100 mW, 0402 [1005 Metric], Thick Film, General Purpose"
				(at 0 0 0)
				(effects
					(font
						(size 1.27 1.27)
					)
					(hide yes)
				)
			)
			(property "MPN" "ERJ2GE0R00X"
				(at 20.32 -20.32 0)
				(effects
					(font
						(size 1.27 1.27)
						(thickness 0.15)
					)
					(justify left bottom)
					(hide yes)
				)
			)
			(property "Manufacturer" "Panasonic"
				(at 20.32 -22.86 0)
				(effects
					(font
						(size 1.27 1.27)
						(thickness 0.15)
					)
					(justify left bottom)
					(hide yes)
				)
			)
			(property "License" "Apache-2.0"
				(at 20.32 -25.4 0)
				(effects
					(font
						(size 1.27 1.27)
						(thickness 0.15)
					)
					(justify left bottom)
					(hide yes)
				)
			)
			(property "Author" "Antmicro"
				(at 20.32 -27.94 0)
				(effects
					(font
						(size 1.27 1.27)
						(thickness 0.15)
					)
					(justify left bottom)
					(hide yes)
				)
			)
			(property "Val" "0R"
				(at 20.32 -7.62 0)
				(effects
					(font
						(size 1.27 1.27)
						(thickness 0.15)
					)
					(justify left bottom)
				)
			)
			(property "Tolerance" "~"
				(at 20.32 -10.16 0)
				(effects
					(font
						(size 1.27 1.27)
					)
					(justify left bottom)
					(hide yes)
				)
			)
			(property "Current" "1A"
				(at 20.32 -30.48 0)
				(effects
					(font
						(size 1.27 1.27)
						(thickness 0.15)
					)
					(justify left bottom)
					(hide yes)
				)
			)
			(property "ki_keywords" "0402, SMT, RESISTOR, PASSIVE"
				(at 0 0 0)
				(effects
					(font
						(size 1.27 1.27)
					)
					(hide yes)
				)
			)
			(symbol "R_0R_0402_0_1"
				(rectangle
					(start 0.635 0.889)
					(end 4.445 -0.889)
					(stroke
						(width 0.254)
						(type default)
					)
					(fill
						(type none)
					)
				)
			)
			(symbol "R_0R_0402_1_1"
				(pin passive line
					(at 0 0 0)
					(length 0.635)
					(name "~"
						(effects
							(font
								(size 1.27 1.27)
							)
						)
					)
					(number "1"
						(effects
							(font
								(size 1.27 1.27)
							)
						)
					)
				)
				(pin passive line
					(at 5.08 0 180)
					(length 0.635)
					(name "~"
						(effects
							(font
								(size 1.27 1.27)
							)
						)
					)
					(number "2"
						(effects
							(font
								(size 1.27 1.27)
							)
						)
					)
				)
			)
		)
	(symbol "antmicroResistors0402:R_100R_0402"
			(pin_numbers
				(hide yes)
			)
			(pin_names
				(hide yes)
			)
			(exclude_from_sim no)
			(in_bom yes)
			(on_board yes)
			(property "Reference" "R"
				(at 20.32 -5.08 0)
				(effects
					(font
						(size 1.27 1.27)
						(thickness 0.15)
					)
					(justify left bottom)
				)
			)
			(property "Value" "R_100R_0402"
				(at 20.32 -12.7 0)
				(effects
					(font
						(size 1.27 1.27)
						(thickness 0.15)
					)
					(justify left bottom)
					(hide yes)
				)
			)
			(property "Footprint" "antmicro-footprints:R_0402_1005Metric"
				(at 20.32 -15.24 0)
				(effects
					(font
						(size 1.27 1.27)
						(thickness 0.15)
					)
					(justify left bottom)
					(hide yes)
				)
			)
			(property "Datasheet" "https://www.bourns.com/docs/product-datasheets/cr.pdf"
				(at 20.32 -17.78 0)
				(effects
					(font
						(size 1.27 1.27)
						(thickness 0.15)
					)
					(justify left bottom)
					(hide yes)
				)
			)
			(property "Description" "SMD Chip Resistor, 100 ohm, ± 1%, 62.5 mW, 0402 [1005 Metric], Thick Film, General Purpose"
				(at 0 0 0)
				(effects
					(font
						(size 1.27 1.27)
					)
					(hide yes)
				)
			)
			(property "MPN" "CR0402-FX-1000GLF"
				(at 20.32 -20.32 0)
				(effects
					(font
						(size 1.27 1.27)
						(thickness 0.15)
					)
					(justify left bottom)
					(hide yes)
				)
			)
			(property "Manufacturer" "Bourns"
				(at 20.32 -22.86 0)
				(effects
					(font
						(size 1.27 1.27)
						(thickness 0.15)
					)
					(justify left bottom)
					(hide yes)
				)
			)
			(property "License" "Apache-2.0"
				(at 20.32 -25.4 0)
				(effects
					(font
						(size 1.27 1.27)
						(thickness 0.15)
					)
					(justify left bottom)
					(hide yes)
				)
			)
			(property "Author" "Antmicro"
				(at 20.32 -27.94 0)
				(effects
					(font
						(size 1.27 1.27)
						(thickness 0.15)
					)
					(justify left bottom)
					(hide yes)
				)
			)
			(property "Val" "100R"
				(at 20.32 -7.62 0)
				(effects
					(font
						(size 1.27 1.27)
						(thickness 0.15)
					)
					(justify left bottom)
				)
			)
			(property "Tolerance" "1%"
				(at 20.32 -10.16 0)
				(effects
					(font
						(size 1.27 1.27)
					)
					(justify left bottom)
					(hide yes)
				)
			)
			(property "ki_keywords" "0402, SMT, RESISTOR, PASSIVE"
				(at 0 0 0)
				(effects
					(font
						(size 1.27 1.27)
					)
					(hide yes)
				)
			)
			(symbol "R_100R_0402_0_1"
				(rectangle
					(start 0.635 0.889)
					(end 4.445 -0.889)
					(stroke
						(width 0.254)
						(type default)
					)
					(fill
						(type none)
					)
				)
			)
			(symbol "R_100R_0402_1_1"
				(pin passive line
					(at 0 0 0)
					(length 0.635)
					(name "~"
						(effects
							(font
								(size 1.27 1.27)
							)
						)
					)
					(number "1"
						(effects
							(font
								(size 1.27 1.27)
							)
						)
					)
				)
				(pin passive line
					(at 5.08 0 180)
					(length 0.635)
					(name "~"
						(effects
							(font
								(size 1.27 1.27)
							)
						)
					)
					(number "2"
						(effects
							(font
								(size 1.27 1.27)
							)
						)
					)
				)
			)
		)
	(symbol "antmicroResistors0402:R_100k_0402"
			(pin_numbers
				(hide yes)
			)
			(pin_names
				(hide yes)
			)
			(exclude_from_sim no)
			(in_bom yes)
			(on_board yes)
			(property "Reference" "R"
				(at 20.32 -5.08 0)
				(effects
					(font
						(size 1.27 1.27)
						(thickness 0.15)
					)
					(justify left bottom)
				)
			)
			(property "Value" "R_100k_0402"
				(at 20.32 -12.7 0)
				(effects
					(font
						(size 1.27 1.27)
						(thickness 0.15)
					)
					(justify left bottom)
					(hide yes)
				)
			)
			(property "Footprint" "antmicro-footprints:R_0402_1005Metric"
				(at 20.32 -15.24 0)
				(effects
					(font
						(size 1.27 1.27)
						(thickness 0.15)
					)
					(justify left bottom)
					(hide yes)
				)
			)
			(property "Datasheet" "https://www.bourns.com/docs/product-datasheets/cr.pdf"
				(at 20.32 -17.78 0)
				(effects
					(font
						(size 1.27 1.27)
						(thickness 0.15)
					)
					(justify left bottom)
					(hide yes)
				)
			)
			(property "Description" "SMD Chip Resistor, 100 kohm, ± 1%, 62.5 mW, 0402 [1005 Metric], Thick Film, General Purpose"
				(at 0 0 0)
				(effects
					(font
						(size 1.27 1.27)
					)
					(hide yes)
				)
			)
			(property "MPN" "CR0402-FX-1003GLF"
				(at 20.32 -20.32 0)
				(effects
					(font
						(size 1.27 1.27)
						(thickness 0.15)
					)
					(justify left bottom)
					(hide yes)
				)
			)
			(property "Manufacturer" "Bourns"
				(at 20.32 -22.86 0)
				(effects
					(font
						(size 1.27 1.27)
						(thickness 0.15)
					)
					(justify left bottom)
					(hide yes)
				)
			)
			(property "License" "Apache-2.0"
				(at 20.32 -25.4 0)
				(effects
					(font
						(size 1.27 1.27)
						(thickness 0.15)
					)
					(justify left bottom)
					(hide yes)
				)
			)
			(property "Author" "Antmicro"
				(at 20.32 -27.94 0)
				(effects
					(font
						(size 1.27 1.27)
						(thickness 0.15)
					)
					(justify left bottom)
					(hide yes)
				)
			)
			(property "Val" "100k"
				(at 20.32 -7.62 0)
				(effects
					(font
						(size 1.27 1.27)
						(thickness 0.15)
					)
					(justify left bottom)
				)
			)
			(property "Tolerance" "1%"
				(at 20.32 -10.16 0)
				(effects
					(font
						(size 1.27 1.27)
					)
					(justify left bottom)
					(hide yes)
				)
			)
			(property "ki_keywords" "0402, SMT, RESISTOR, PASSIVE"
				(at 0 0 0)
				(effects
					(font
						(size 1.27 1.27)
					)
					(hide yes)
				)
			)
			(symbol "R_100k_0402_0_1"
				(rectangle
					(start 0.635 0.889)
					(end 4.445 -0.889)
					(stroke
						(width 0.254)
						(type default)
					)
					(fill
						(type none)
					)
				)
			)
			(symbol "R_100k_0402_1_1"
				(pin passive line
					(at 0 0 0)
					(length 0.635)
					(name "~"
						(effects
							(font
								(size 1.27 1.27)
							)
						)
					)
					(number "1"
						(effects
							(font
								(size 1.27 1.27)
							)
						)
					)
				)
				(pin passive line
					(at 5.08 0 180)
					(length 0.635)
					(name "~"
						(effects
							(font
								(size 1.27 1.27)
							)
						)
					)
					(number "2"
						(effects
							(font
								(size 1.27 1.27)
							)
						)
					)
				)
			)
		)
	(symbol "antmicroResistors0402:R_1M_0402"
			(pin_numbers
				(hide yes)
			)
			(pin_names
				(hide yes)
			)
			(exclude_from_sim no)
			(in_bom yes)
			(on_board yes)
			(property "Reference" "R"
				(at 20.32 -5.08 0)
				(effects
					(font
						(size 1.27 1.27)
						(thickness 0.15)
					)
					(justify left bottom)
				)
			)
			(property "Value" "R_1M_0402"
				(at 20.32 -12.7 0)
				(effects
					(font
						(size 1.27 1.27)
						(thickness 0.15)
					)
					(justify left bottom)
					(hide yes)
				)
			)
			(property "Footprint" "antmicro-footprints:R_0402_1005Metric"
				(at 20.32 -15.24 0)
				(effects
					(font
						(size 1.27 1.27)
						(thickness 0.15)
					)
					(justify left bottom)
					(hide yes)
				)
			)
			(property "Datasheet" "https://www.bourns.com/docs/product-datasheets/cr.pdf"
				(at 20.32 -17.78 0)
				(effects
					(font
						(size 1.27 1.27)
						(thickness 0.15)
					)
					(justify left bottom)
					(hide yes)
				)
			)
			(property "Description" "SMD Chip Resistor, 1 Mohm, ± 1%, 62.5 mW, 0402 [1005 Metric], Thick Film, General Purpose"
				(at 0 0 0)
				(effects
					(font
						(size 1.27 1.27)
					)
					(hide yes)
				)
			)
			(property "MPN" "CR0402-FX-1004GLF"
				(at 20.32 -20.32 0)
				(effects
					(font
						(size 1.27 1.27)
						(thickness 0.15)
					)
					(justify left bottom)
					(hide yes)
				)
			)
			(property "Manufacturer" "Bourns"
				(at 20.32 -22.86 0)
				(effects
					(font
						(size 1.27 1.27)
						(thickness 0.15)
					)
					(justify left bottom)
					(hide yes)
				)
			)
			(property "License" "Apache-2.0"
				(at 20.32 -25.4 0)
				(effects
					(font
						(size 1.27 1.27)
						(thickness 0.15)
					)
					(justify left bottom)
					(hide yes)
				)
			)
			(property "Author" "Antmicro"
				(at 20.32 -27.94 0)
				(effects
					(font
						(size 1.27 1.27)
						(thickness 0.15)
					)
					(justify left bottom)
					(hide yes)
				)
			)
			(property "Val" "1M"
				(at 20.32 -7.62 0)
				(effects
					(font
						(size 1.27 1.27)
						(thickness 0.15)
					)
					(justify left bottom)
				)
			)
			(property "Tolerance" "1%"
				(at 20.32 -10.16 0)
				(effects
					(font
						(size 1.27 1.27)
					)
					(justify left bottom)
					(hide yes)
				)
			)
			(property "ki_keywords" "0402, SMT, RESISTOR, PASSIVE"
				(at 0 0 0)
				(effects
					(font
						(size 1.27 1.27)
					)
					(hide yes)
				)
			)
			(symbol "R_1M_0402_0_1"
				(rectangle
					(start 0.635 0.889)
					(end 4.445 -0.889)
					(stroke
						(width 0.254)
						(type default)
					)
					(fill
						(type none)
					)
				)
			)
			(symbol "R_1M_0402_1_1"
				(pin passive line
					(at 0 0 0)
					(length 0.635)
					(name "~"
						(effects
							(font
								(size 1.27 1.27)
							)
						)
					)
					(number "1"
						(effects
							(font
								(size 1.27 1.27)
							)
						)
					)
				)
				(pin passive line
					(at 5.08 0 180)
					(length 0.635)
					(name "~"
						(effects
							(font
								(size 1.27 1.27)
							)
						)
					)
					(number "2"
						(effects
							(font
								(size 1.27 1.27)
							)
						)
					)
				)
			)
		)
	(symbol "antmicroResistors0402:R_1k_0402"
			(pin_numbers
				(hide yes)
			)
			(pin_names
				(hide yes)
			)
			(exclude_from_sim no)
			(in_bom yes)
			(on_board yes)
			(property "Reference" "R"
				(at 20.32 -5.08 0)
				(effects
					(font
						(size 1.27 1.27)
						(thickness 0.15)
					)
					(justify left bottom)
				)
			)
			(property "Value" "R_1k_0402"
				(at 20.32 -12.7 0)
				(effects
					(font
						(size 1.27 1.27)
						(thickness 0.15)
					)
					(justify left bottom)
					(hide yes)
				)
			)
			(property "Footprint" "antmicro-footprints:R_0402_1005Metric"
				(at 20.32 -15.24 0)
				(effects
					(font
						(size 1.27 1.27)
						(thickness 0.15)
					)
					(justify left bottom)
					(hide yes)
				)
			)
			(property "Datasheet" "https://www.bourns.com/docs/product-datasheets/cr.pdf"
				(at 20.32 -17.78 0)
				(effects
					(font
						(size 1.27 1.27)
						(thickness 0.15)
					)
					(justify left bottom)
					(hide yes)
				)
			)
			(property "Description" "SMD Chip Resistor, 1 kohm, ± 1%, 63 mW, 0402 [1005 Metric], Thick Film, General Purpose"
				(at 0 0 0)
				(effects
					(font
						(size 1.27 1.27)
					)
					(hide yes)
				)
			)
			(property "MPN" "CR0402-FX-1001GLF"
				(at 20.32 -20.32 0)
				(effects
					(font
						(size 1.27 1.27)
						(thickness 0.15)
					)
					(justify left bottom)
					(hide yes)
				)
			)
			(property "Manufacturer" "Bourns"
				(at 20.32 -22.86 0)
				(effects
					(font
						(size 1.27 1.27)
						(thickness 0.15)
					)
					(justify left bottom)
					(hide yes)
				)
			)
			(property "License" "Apache-2.0"
				(at 20.32 -25.4 0)
				(effects
					(font
						(size 1.27 1.27)
						(thickness 0.15)
					)
					(justify left bottom)
					(hide yes)
				)
			)
			(property "Author" "Antmicro"
				(at 20.32 -27.94 0)
				(effects
					(font
						(size 1.27 1.27)
						(thickness 0.15)
					)
					(justify left bottom)
					(hide yes)
				)
			)
			(property "Val" "1k"
				(at 20.32 -7.62 0)
				(effects
					(font
						(size 1.27 1.27)
						(thickness 0.15)
					)
					(justify left bottom)
				)
			)
			(property "Tolerance" "1%"
				(at 20.32 -10.16 0)
				(effects
					(font
						(size 1.27 1.27)
					)
					(justify left bottom)
					(hide yes)
				)
			)
			(property "ki_keywords" "0402, SMT, RESISTOR, PASSIVE"
				(at 0 0 0)
				(effects
					(font
						(size 1.27 1.27)
					)
					(hide yes)
				)
			)
			(symbol "R_1k_0402_0_1"
				(rectangle
					(start 0.635 0.889)
					(end 4.445 -0.889)
					(stroke
						(width 0.254)
						(type default)
					)
					(fill
						(type none)
					)
				)
			)
			(symbol "R_1k_0402_1_1"
				(pin passive line
					(at 0 0 0)
					(length 0.635)
					(name "~"
						(effects
							(font
								(size 1.27 1.27)
							)
						)
					)
					(number "1"
						(effects
							(font
								(size 1.27 1.27)
							)
						)
					)
				)
				(pin passive line
					(at 5.08 0 180)
					(length 0.635)
					(name "~"
						(effects
							(font
								(size 1.27 1.27)
							)
						)
					)
					(number "2"
						(effects
							(font
								(size 1.27 1.27)
							)
						)
					)
				)
			)
		)
	(symbol "antmicroResistors0402:R_470R_0402"
			(pin_numbers
				(hide yes)
			)
			(pin_names
				(hide yes)
			)
			(exclude_from_sim no)
			(in_bom yes)
			(on_board yes)
			(property "Reference" "R"
				(at 20.32 -5.08 0)
				(effects
					(font
						(size 1.27 1.27)
						(thickness 0.15)
					)
					(justify left bottom)
				)
			)
			(property "Value" "R_470R_0402"
				(at 20.32 -12.7 0)
				(effects
					(font
						(size 1.27 1.27)
						(thickness 0.15)
					)
					(justify left bottom)
					(hide yes)
				)
			)
			(property "Footprint" "antmicro-footprints:R_0402_1005Metric"
				(at 20.32 -15.24 0)
				(effects
					(font
						(size 1.27 1.27)
						(thickness 0.15)
					)
					(justify left bottom)
					(hide yes)
				)
			)
			(property "Datasheet" "https://www.bourns.com/docs/product-datasheets/cr.pdf"
				(at 20.32 -17.78 0)
				(effects
					(font
						(size 1.27 1.27)
						(thickness 0.15)
					)
					(justify left bottom)
					(hide yes)
				)
			)
			(property "Description" "SMD Chip Resistor, 470 ohm, ± 1%, 62.5 mW, 0402 [1005 Metric], Thick Film, General Purpose"
				(at 0 0 0)
				(effects
					(font
						(size 1.27 1.27)
					)
					(hide yes)
				)
			)
			(property "MPN" "CR0402-FX-4700GLF"
				(at 20.32 -20.32 0)
				(effects
					(font
						(size 1.27 1.27)
						(thickness 0.15)
					)
					(justify left bottom)
					(hide yes)
				)
			)
			(property "Manufacturer" "Bourns"
				(at 20.32 -22.86 0)
				(effects
					(font
						(size 1.27 1.27)
						(thickness 0.15)
					)
					(justify left bottom)
					(hide yes)
				)
			)
			(property "License" "Apache-2.0"
				(at 20.32 -25.4 0)
				(effects
					(font
						(size 1.27 1.27)
						(thickness 0.15)
					)
					(justify left bottom)
					(hide yes)
				)
			)
			(property "Author" "Antmicro"
				(at 20.32 -27.94 0)
				(effects
					(font
						(size 1.27 1.27)
						(thickness 0.15)
					)
					(justify left bottom)
					(hide yes)
				)
			)
			(property "Val" "470R"
				(at 20.32 -7.62 0)
				(effects
					(font
						(size 1.27 1.27)
						(thickness 0.15)
					)
					(justify left bottom)
				)
			)
			(property "Tolerance" "1%"
				(at 20.32 -10.16 0)
				(effects
					(font
						(size 1.27 1.27)
					)
					(justify left bottom)
					(hide yes)
				)
			)
			(property "ki_keywords" "0402, SMT, RESISTOR, PASSIVE"
				(at 0 0 0)
				(effects
					(font
						(size 1.27 1.27)
					)
					(hide yes)
				)
			)
			(symbol "R_470R_0402_0_1"
				(rectangle
					(start 0.635 0.889)
					(end 4.445 -0.889)
					(stroke
						(width 0.254)
						(type default)
					)
					(fill
						(type none)
					)
				)
			)
			(symbol "R_470R_0402_1_1"
				(pin passive line
					(at 0 0 0)
					(length 0.635)
					(name "~"
						(effects
							(font
								(size 1.27 1.27)
							)
						)
					)
					(number "1"
						(effects
							(font
								(size 1.27 1.27)
							)
						)
					)
				)
				(pin passive line
					(at 5.08 0 180)
					(length 0.635)
					(name "~"
						(effects
							(font
								(size 1.27 1.27)
							)
						)
					)
					(number "2"
						(effects
							(font
								(size 1.27 1.27)
							)
						)
					)
				)
			)
		)
	(symbol "antmicroResistors0402:R_5k1_0402"
			(pin_numbers
				(hide yes)
			)
			(pin_names
				(hide yes)
			)
			(exclude_from_sim no)
			(in_bom yes)
			(on_board yes)
			(property "Reference" "R"
				(at 20.32 -5.08 0)
				(effects
					(font
						(size 1.27 1.27)
						(thickness 0.15)
					)
					(justify left bottom)
				)
			)
			(property "Value" "R_5k1_0402"
				(at 20.32 -12.7 0)
				(effects
					(font
						(size 1.27 1.27)
						(thickness 0.15)
					)
					(justify left bottom)
					(hide yes)
				)
			)
			(property "Footprint" "antmicro-footprints:R_0402_1005Metric"
				(at 20.32 -15.24 0)
				(effects
					(font
						(size 1.27 1.27)
						(thickness 0.15)
					)
					(justify left bottom)
					(hide yes)
				)
			)
			(property "Datasheet" "https://www.bourns.com/docs/product-datasheets/cr.pdf"
				(at 20.32 -17.78 0)
				(effects
					(font
						(size 1.27 1.27)
						(thickness 0.15)
					)
					(justify left bottom)
					(hide yes)
				)
			)
			(property "Description" "SMD Chip Resistor, 5.1 kohm, ± 1%, 63 mW, 0402 [1005 Metric], Thick Film, General Purpose"
				(at 0 0 0)
				(effects
					(font
						(size 1.27 1.27)
					)
					(hide yes)
				)
			)
			(property "MPN" "CR0402-FX-5101GLF"
				(at 20.32 -20.32 0)
				(effects
					(font
						(size 1.27 1.27)
						(thickness 0.15)
					)
					(justify left bottom)
					(hide yes)
				)
			)
			(property "Manufacturer" "Bourns"
				(at 20.32 -22.86 0)
				(effects
					(font
						(size 1.27 1.27)
						(thickness 0.15)
					)
					(justify left bottom)
					(hide yes)
				)
			)
			(property "License" "Apache-2.0"
				(at 20.32 -25.4 0)
				(effects
					(font
						(size 1.27 1.27)
						(thickness 0.15)
					)
					(justify left bottom)
					(hide yes)
				)
			)
			(property "Author" "Antmicro"
				(at 20.32 -27.94 0)
				(effects
					(font
						(size 1.27 1.27)
						(thickness 0.15)
					)
					(justify left bottom)
					(hide yes)
				)
			)
			(property "Val" "5k1"
				(at 20.32 -7.62 0)
				(effects
					(font
						(size 1.27 1.27)
						(thickness 0.15)
					)
					(justify left bottom)
				)
			)
			(property "Tolerance" "1%"
				(at 20.32 -10.16 0)
				(effects
					(font
						(size 1.27 1.27)
					)
					(justify left bottom)
					(hide yes)
				)
			)
			(property "ki_keywords" "0402, SMT, RESISTOR, PASSIVE"
				(at 0 0 0)
				(effects
					(font
						(size 1.27 1.27)
					)
					(hide yes)
				)
			)
			(symbol "R_5k1_0402_0_1"
				(rectangle
					(start 0.635 0.889)
					(end 4.445 -0.889)
					(stroke
						(width 0.254)
						(type default)
					)
					(fill
						(type none)
					)
				)
			)
			(symbol "R_5k1_0402_1_1"
				(pin passive line
					(at 0 0 0)
					(length 0.635)
					(name "~"
						(effects
							(font
								(size 1.27 1.27)
							)
						)
					)
					(number "1"
						(effects
							(font
								(size 1.27 1.27)
							)
						)
					)
				)
				(pin passive line
					(at 5.08 0 180)
					(length 0.635)
					(name "~"
						(effects
							(font
								(size 1.27 1.27)
							)
						)
					)
					(number "2"
						(effects
							(font
								(size 1.27 1.27)
							)
						)
					)
				)
			)
		)
	(symbol "antmicroResonators:Resonator_32.768kHz_ECX-31B"
			(pin_names
				(hide yes)
			)
			(exclude_from_sim no)
			(in_bom yes)
			(on_board yes)
			(property "Reference" "Y"
				(at 15.24 -5.08 0)
				(effects
					(font
						(size 1.27 1.27)
						(thickness 0.15)
					)
					(justify left bottom)
				)
			)
			(property "Value" "Resonator_32.768kHz_ECX-31B"
				(at 15.24 -15.24 0)
				(effects
					(font
						(size 1.27 1.27)
						(thickness 0.15)
					)
					(justify left bottom)
					(hide yes)
				)
			)
			(property "Footprint" "antmicro-footprints:Resonator_SMD_ECS_ECX-31B_3.2x1.5x0.9mm"
				(at 15.24 -17.78 0)
				(effects
					(font
						(size 1.27 1.27)
						(thickness 0.15)
					)
					(justify left bottom)
					(hide yes)
				)
			)
			(property "Datasheet" "http://www.ecsxtal.com/store/pdf/ecx-31b.pdf"
				(at 15.24 -20.32 0)
				(effects
					(font
						(size 1.27 1.27)
						(thickness 0.15)
					)
					(justify left bottom)
					(hide yes)
				)
			)
			(property "Description" "Crystal, 32.768 kHz, SMT, 3.2mm x 1.5mm, 12.5 pF, 20 ppm, ECX-31B"
				(at 0 0 0)
				(effects
					(font
						(size 1.27 1.27)
					)
					(hide yes)
				)
			)
			(property "MPN" "ECS-.327-12.5-34B-TR"
				(at 15.24 -7.62 0)
				(effects
					(font
						(size 1.27 1.27)
						(thickness 0.15)
					)
					(justify left bottom)
				)
			)
			(property "Manufacturer" "ECS Inc. International"
				(at 15.24 -10.16 0)
				(effects
					(font
						(size 1.27 1.27)
						(thickness 0.15)
					)
					(justify left bottom)
					(hide yes)
				)
			)
			(property "Val" "32.768 kHz"
				(at 15.24 -12.7 0)
				(effects
					(font
						(size 1.27 1.27)
						(thickness 0.15)
					)
					(justify left bottom)
				)
			)
			(property "Author" "Antmicro"
				(at 15.24 -22.86 0)
				(effects
					(font
						(size 1.27 1.27)
						(thickness 0.15)
					)
					(justify left bottom)
					(hide yes)
				)
			)
			(property "License" "Apache-2.0"
				(at 15.24 -25.4 0)
				(effects
					(font
						(size 1.27 1.27)
						(thickness 0.15)
					)
					(justify left bottom)
					(hide yes)
				)
			)
			(property "ki_keywords" "SMT, OSCILLATOR"
				(at 0 0 0)
				(effects
					(font
						(size 1.27 1.27)
					)
					(hide yes)
				)
			)
			(symbol "Resonator_32.768kHz_ECX-31B_1_1"
				(polyline
					(pts
						(xy 2.54 1.27) (xy 2.54 -1.27)
					)
					(stroke
						(width 0.254)
						(type default)
					)
					(fill
						(type background)
					)
				)
				(rectangle
					(start 3.175 1.905)
					(end 4.445 -1.905)
					(stroke
						(width 0.254)
						(type default)
					)
					(fill
						(type background)
					)
				)
				(polyline
					(pts
						(xy 5.08 1.27) (xy 5.08 -1.27)
					)
					(stroke
						(width 0.254)
						(type default)
					)
					(fill
						(type background)
					)
				)
				(pin passive line
					(at 0 0 0)
					(length 2.54)
					(name "~"
						(effects
							(font
								(size 1.27 1.27)
							)
						)
					)
					(number "1"
						(effects
							(font
								(size 1.27 1.27)
							)
						)
					)
				)
				(pin passive line
					(at 7.62 0 180)
					(length 2.54)
					(name "~"
						(effects
							(font
								(size 1.27 1.27)
							)
						)
					)
					(number "2"
						(effects
							(font
								(size 1.27 1.27)
							)
						)
					)
				)
			)
		)
	(symbol "antmicroResonators:Resonator_8MHz_ABM3B"
			(pin_names
				(hide yes)
			)
			(exclude_from_sim no)
			(in_bom yes)
			(on_board yes)
			(property "Reference" "Y"
				(at 15.24 -5.08 0)
				(effects
					(font
						(size 1.27 1.27)
						(thickness 0.15)
					)
					(justify left bottom)
				)
			)
			(property "Value" "Resonator_8MHz_ABM3B"
				(at 15.24 -12.7 0)
				(effects
					(font
						(size 1.27 1.27)
						(thickness 0.15)
					)
					(justify left bottom)
					(hide yes)
				)
			)
			(property "Footprint" "antmicro-footprints:Resonator_SMD_Abracon_ABM3B_5x3.2mm"
				(at 15.24 -15.24 0)
				(effects
					(font
						(size 1.27 1.27)
						(thickness 0.15)
					)
					(justify left bottom)
					(hide yes)
				)
			)
			(property "Datasheet" "https://abracon.com/Resonators/abm3b.pdf"
				(at 15.24 -17.78 0)
				(effects
					(font
						(size 1.27 1.27)
						(thickness 0.15)
					)
					(justify left bottom)
					(hide yes)
				)
			)
			(property "Description" "Crystal, 8 MHz, SMT, 5mm x 3.2mm, 10 ppm, 10 pF, 10 ppm"
				(at 0 0 0)
				(effects
					(font
						(size 1.27 1.27)
					)
					(hide yes)
				)
			)
			(property "MPN" "ABM3B-8.000MHZ-10-1-U-T"
				(at 15.24 -7.62 0)
				(effects
					(font
						(size 1.27 1.27)
						(thickness 0.15)
					)
					(justify left bottom)
				)
			)
			(property "Manufacturer" "Abracon"
				(at 15.24 -20.32 0)
				(effects
					(font
						(size 1.27 1.27)
						(thickness 0.15)
					)
					(justify left bottom)
					(hide yes)
				)
			)
			(property "Author" "Antmicro"
				(at 15.24 -22.86 0)
				(effects
					(font
						(size 1.27 1.27)
						(thickness 0.15)
					)
					(justify left bottom)
					(hide yes)
				)
			)
			(property "License" "Apache-2.0"
				(at 15.24 -25.4 0)
				(effects
					(font
						(size 1.27 1.27)
						(thickness 0.15)
					)
					(justify left bottom)
					(hide yes)
				)
			)
			(property "Val" "8 MHz"
				(at 15.24 -10.16 0)
				(effects
					(font
						(size 1.27 1.27)
						(thickness 0.15)
					)
					(justify left bottom)
				)
			)
			(property "ki_keywords" "SMT, CERAMIC, OSCILLATOR"
				(at 0 0 0)
				(effects
					(font
						(size 1.27 1.27)
					)
					(hide yes)
				)
			)
			(symbol "Resonator_8MHz_ABM3B_1_1"
				(polyline
					(pts
						(xy 1.905 1.905) (xy 1.905 2.54) (xy 5.715 2.54) (xy 5.715 1.905)
					)
					(stroke
						(width 0.254)
						(type default)
					)
					(fill
						(type none)
					)
				)
				(polyline
					(pts
						(xy 1.905 -1.905) (xy 1.905 -2.54) (xy 5.715 -2.54) (xy 5.715 -1.905)
					)
					(stroke
						(width 0.254)
						(type default)
					)
					(fill
						(type none)
					)
				)
				(polyline
					(pts
						(xy 2.54 1.27) (xy 2.54 -1.27)
					)
					(stroke
						(width 0.254)
						(type default)
					)
					(fill
						(type background)
					)
				)
				(rectangle
					(start 3.175 1.905)
					(end 4.445 -1.905)
					(stroke
						(width 0.254)
						(type default)
					)
					(fill
						(type background)
					)
				)
				(polyline
					(pts
						(xy 5.08 1.27) (xy 5.08 -1.27)
					)
					(stroke
						(width 0.254)
						(type default)
					)
					(fill
						(type background)
					)
				)
				(pin passive line
					(at 0 0 0)
					(length 2.54)
					(name "~"
						(effects
							(font
								(size 1.27 1.27)
							)
						)
					)
					(number "1"
						(effects
							(font
								(size 1.27 1.27)
							)
						)
					)
				)
				(pin passive line
					(at 3.81 -5.08 90)
					(length 2.54)
					(name "SH"
						(effects
							(font
								(size 1.27 1.27)
							)
						)
					)
					(number "2"
						(effects
							(font
								(size 1.27 1.27)
							)
						)
					)
				)
				(pin passive line
					(at 3.81 -5.08 90)
					(length 2.54)
					(hide yes)
					(name "SH"
						(effects
							(font
								(size 1.27 1.27)
							)
						)
					)
					(number "4"
						(effects
							(font
								(size 1.27 1.27)
							)
						)
					)
				)
				(pin passive line
					(at 7.62 0 180)
					(length 2.54)
					(name "~"
						(effects
							(font
								(size 1.27 1.27)
							)
						)
					)
					(number "3"
						(effects
							(font
								(size 1.27 1.27)
							)
						)
					)
				)
			)
		)
	(symbol "antmicroTVSDiodes:ESD9X5.0ST5G"
			(pin_numbers
				(hide yes)
			)
			(pin_names
				(hide yes)
			)
			(exclude_from_sim no)
			(in_bom yes)
			(on_board yes)
			(property "Reference" "D"
				(at 21.59 -2.54 0)
				(effects
					(font
						(size 1.27 1.27)
						(thickness 0.15)
					)
					(justify left bottom)
				)
			)
			(property "Value" "ESD9X5.0ST5G"
				(at 21.59 -15.24 0)
				(effects
					(font
						(size 1.27 1.27)
						(thickness 0.15)
					)
					(justify left bottom)
					(hide yes)
				)
			)
			(property "Footprint" "antmicro-footprints:SOD-923"
				(at 21.59 -7.62 0)
				(effects
					(font
						(size 1.27 1.27)
						(thickness 0.15)
					)
					(justify left bottom)
					(hide yes)
				)
			)
			(property "Datasheet" "https://www.onsemi.com/pdf/datasheet/esd9x3.3st5g-d.pdf"
				(at 21.59 -10.16 0)
				(effects
					(font
						(size 1.27 1.27)
						(thickness 0.15)
					)
					(justify left bottom)
					(hide yes)
				)
			)
			(property "Description" "Unidirectional TVS, 30 kV,  SOD-923, 5 V, 65 pF"
				(at 0 0 0)
				(effects
					(font
						(size 1.27 1.27)
					)
					(hide yes)
				)
			)
			(property "Manufacturer" "ON Semiconductor"
				(at 21.59 -12.7 0)
				(effects
					(font
						(size 1.27 1.27)
						(thickness 0.15)
					)
					(justify left bottom)
					(hide yes)
				)
			)
			(property "MPN" "ESD9X5.0ST5G"
				(at 21.59 -5.08 0)
				(effects
					(font
						(size 1.27 1.27)
						(thickness 0.15)
					)
					(justify left bottom)
				)
			)
			(property "Author" "Antmicro"
				(at 21.59 -17.78 0)
				(effects
					(font
						(size 1.27 1.27)
						(thickness 0.15)
					)
					(justify left bottom)
					(hide yes)
				)
			)
			(property "License" "Apache-2.0"
				(at 21.59 -20.32 0)
				(effects
					(font
						(size 1.27 1.27)
						(thickness 0.15)
					)
					(justify left bottom)
					(hide yes)
				)
			)
			(property "ki_keywords" "DIODE, SEMICONDUCTOR, TVS, ESD"
				(at 0 0 0)
				(effects
					(font
						(size 1.27 1.27)
					)
					(hide yes)
				)
			)
			(symbol "ESD9X5.0ST5G_0_1"
				(polyline
					(pts
						(xy 1.905 0) (xy 0.635 0)
					)
					(stroke
						(width 0)
						(type default)
					)
					(fill
						(type none)
					)
				)
				(polyline
					(pts
						(xy 4.445 0) (xy 3.175 0)
					)
					(stroke
						(width 0)
						(type default)
					)
					(fill
						(type none)
					)
				)
			)
			(symbol "ESD9X5.0ST5G_1_1"
				(polyline
					(pts
						(xy 1.778 1.016) (xy 1.397 1.016)
					)
					(stroke
						(width 0.254)
						(type default)
					)
					(fill
						(type none)
					)
				)
				(polyline
					(pts
						(xy 1.778 1.016) (xy 1.778 -1.016)
					)
					(stroke
						(width 0.254)
						(type default)
					)
					(fill
						(type none)
					)
				)
				(polyline
					(pts
						(xy 2.159 -1.016) (xy 1.778 -1.016)
					)
					(stroke
						(width 0.254)
						(type default)
					)
					(fill
						(type none)
					)
				)
				(polyline
					(pts
						(xy 3.302 1.016) (xy 3.302 -1.016) (xy 1.778 0) (xy 3.302 1.016)
					)
					(stroke
						(width 0.254)
						(type default)
					)
					(fill
						(type outline)
					)
				)
				(pin passive line
					(at 0 0 0)
					(length 0.635)
					(name "C"
						(effects
							(font
								(size 1.27 1.27)
							)
						)
					)
					(number "1"
						(effects
							(font
								(size 1.27 1.27)
							)
						)
					)
				)
				(pin passive line
					(at 5.08 0 180)
					(length 0.635)
					(name "A"
						(effects
							(font
								(size 1.27 1.27)
							)
						)
					)
					(number "2"
						(effects
							(font
								(size 1.27 1.27)
							)
						)
					)
				)
			)
		)
	(symbol "antmicroTVSDiodes:TPD2E009_SOT-9X3"
			(pin_names
				(hide yes)
			)
			(exclude_from_sim no)
			(in_bom yes)
			(on_board yes)
			(property "Reference" "D"
				(at 15.24 0 0)
				(effects
					(font
						(size 1.27 1.27)
						(thickness 0.15)
					)
					(justify left bottom)
				)
			)
			(property "Value" "TPD2E009_SOT-9X3"
				(at 15.24 -10.16 0)
				(effects
					(font
						(size 1.27 1.27)
						(thickness 0.15)
					)
					(justify left bottom)
					(hide yes)
				)
			)
			(property "Footprint" "antmicro-footprints:SOT-723"
				(at 15.24 -5.08 0)
				(effects
					(font
						(size 1.27 1.27)
						(thickness 0.15)
					)
					(justify left bottom)
					(hide yes)
				)
			)
			(property "Datasheet" "https://www.ti.com/lit/ds/symlink/tpd2e009.pdf?ts=1597910439511&ref_url=https%253A%252F%252Fwww.google.com%252F"
				(at 15.24 -7.62 0)
				(effects
					(font
						(size 1.27 1.27)
						(thickness 0.15)
					)
					(justify left bottom)
					(hide yes)
				)
			)
			(property "Description" "TVS diode array, 8 kV, SOT-723, 5.5 V, 0.9 pF"
				(at 0 0 0)
				(effects
					(font
						(size 1.27 1.27)
					)
					(hide yes)
				)
			)
			(property "MPN" "TPD2E009DRTR"
				(at 15.24 -2.54 0)
				(effects
					(font
						(size 1.27 1.27)
						(thickness 0.15)
					)
					(justify left bottom)
				)
			)
			(property "Manufacturer" "Texas Instruments"
				(at 15.24 -12.7 0)
				(effects
					(font
						(size 1.27 1.27)
						(thickness 0.15)
					)
					(justify left bottom)
					(hide yes)
				)
			)
			(property "Author" "Antmicro"
				(at 15.24 -15.24 0)
				(effects
					(font
						(size 1.27 1.27)
						(thickness 0.15)
					)
					(justify left bottom)
					(hide yes)
				)
			)
			(property "License" "Apache-2.0"
				(at 15.24 -17.78 0)
				(effects
					(font
						(size 1.27 1.27)
						(thickness 0.15)
					)
					(justify left bottom)
					(hide yes)
				)
			)
			(property "ki_keywords" "SMT, DIODE, SEMICONDUCTOR, TVS, ESD"
				(at 0 0 0)
				(effects
					(font
						(size 1.27 1.27)
					)
					(hide yes)
				)
			)
			(symbol "TPD2E009_SOT-9X3_1_1"
				(rectangle
					(start 2.54 2.54)
					(end 8.89 -7.62)
					(stroke
						(width 0.254)
						(type default)
					)
					(fill
						(type background)
					)
				)
				(polyline
					(pts
						(xy 2.54 0) (xy 7.62 0)
					)
					(stroke
						(width 0.254)
						(type default)
					)
					(fill
						(type background)
					)
				)
				(polyline
					(pts
						(xy 2.54 -2.54) (xy 7.62 -2.54)
					)
					(stroke
						(width 0.254)
						(type default)
					)
					(fill
						(type background)
					)
				)
				(polyline
					(pts
						(xy 4.826 -0.635) (xy 5.08 -0.381) (xy 5.08 0.381) (xy 5.334 0.635)
					)
					(stroke
						(width 0.254)
						(type default)
					)
					(fill
						(type background)
					)
				)
				(polyline
					(pts
						(xy 4.826 -3.175) (xy 5.08 -2.921) (xy 5.08 -2.159) (xy 5.334 -1.905)
					)
					(stroke
						(width 0.254)
						(type default)
					)
					(fill
						(type background)
					)
				)
				(polyline
					(pts
						(xy 5.08 0) (xy 3.81 -0.635) (xy 3.81 0.635) (xy 5.08 0)
					)
					(stroke
						(width 0.254)
						(type default)
					)
					(fill
						(type background)
					)
				)
				(polyline
					(pts
						(xy 5.08 0) (xy 6.35 0.635) (xy 6.35 -0.635) (xy 5.08 0)
					)
					(stroke
						(width 0.254)
						(type default)
					)
					(fill
						(type background)
					)
				)
				(polyline
					(pts
						(xy 5.08 -2.54) (xy 3.81 -3.175) (xy 3.81 -1.905) (xy 5.08 -2.54)
					)
					(stroke
						(width 0.254)
						(type default)
					)
					(fill
						(type background)
					)
				)
				(polyline
					(pts
						(xy 6.35 -1.905) (xy 6.35 -3.175) (xy 5.08 -2.54) (xy 6.35 -1.905)
					)
					(stroke
						(width 0.254)
						(type default)
					)
					(fill
						(type background)
					)
				)
				(circle
					(center 7.62 -2.54)
					(radius 0.254)
					(stroke
						(width 0.254)
						(type default)
					)
					(fill
						(type background)
					)
				)
				(polyline
					(pts
						(xy 7.62 -5.08) (xy 2.54 -5.08)
					)
					(stroke
						(width 0.254)
						(type default)
					)
					(fill
						(type background)
					)
				)
				(polyline
					(pts
						(xy 7.62 -5.08) (xy 7.62 0)
					)
					(stroke
						(width 0.254)
						(type default)
					)
					(fill
						(type background)
					)
				)
				(pin passive line
					(at 0 0 0)
					(length 2.54)
					(name "1"
						(effects
							(font
								(size 1.27 1.27)
							)
						)
					)
					(number "1"
						(effects
							(font
								(size 1.27 1.27)
							)
						)
					)
				)
				(pin passive line
					(at 0 -2.54 0)
					(length 2.54)
					(name "2"
						(effects
							(font
								(size 1.27 1.27)
							)
						)
					)
					(number "2"
						(effects
							(font
								(size 1.27 1.27)
							)
						)
					)
				)
				(pin passive line
					(at 0 -5.08 0)
					(length 2.54)
					(name "3"
						(effects
							(font
								(size 1.27 1.27)
							)
						)
					)
					(number "3"
						(effects
							(font
								(size 1.27 1.27)
							)
						)
					)
				)
			)
		)
	(symbol "antmicroTestPoints:TP_1.5mm_SMD"
			(pin_names
				(hide yes)
			)
			(exclude_from_sim no)
			(in_bom no)
			(on_board yes)
			(property "Reference" "TP"
				(at 15.24 -5.08 0)
				(effects
					(font
						(size 1.27 1.27)
						(thickness 0.15)
					)
					(justify left bottom)
				)
			)
			(property "Value" "TP_1.5mm_SMD"
				(at 15.24 -7.62 0)
				(effects
					(font
						(size 1.27 1.27)
						(thickness 0.15)
					)
					(justify left bottom)
					(hide yes)
				)
			)
			(property "Footprint" "antmicro-footprints:TP_SMD_1.5mm"
				(at 15.24 -10.16 0)
				(effects
					(font
						(size 1.27 1.27)
						(thickness 0.15)
					)
					(justify left bottom)
					(hide yes)
				)
			)
			(property "Datasheet" ""
				(at 17.78 -12.7 0)
				(effects
					(font
						(size 1.27 1.27)
						(thickness 0.15)
					)
					(justify left bottom)
					(hide yes)
				)
			)
			(property "Description" "test point, SMT"
				(at 0 0 0)
				(effects
					(font
						(size 1.27 1.27)
					)
					(hide yes)
				)
			)
			(property "MPN" ""
				(at 0 0 0)
				(effects
					(font
						(size 1.27 1.27)
					)
					(hide yes)
				)
			)
			(property "Manufacturer" ""
				(at 0 0 0)
				(effects
					(font
						(size 1.27 1.27)
					)
					(hide yes)
				)
			)
			(property "Author" "Antmicro"
				(at 15.24 -15.24 0)
				(effects
					(font
						(size 1.27 1.27)
						(thickness 0.15)
					)
					(justify left bottom)
					(hide yes)
				)
			)
			(property "License" "Apache-2.0"
				(at 15.24 -17.78 0)
				(effects
					(font
						(size 1.27 1.27)
						(thickness 0.15)
					)
					(justify left bottom)
					(hide yes)
				)
			)
			(property "ki_keywords" "TESTPOINT"
				(at 0 0 0)
				(effects
					(font
						(size 1.27 1.27)
					)
					(hide yes)
				)
			)
			(symbol "TP_1.5mm_SMD_1_1"
				(circle
					(center 3.175 0)
					(radius 0.635)
					(stroke
						(width 0.254)
						(type default)
					)
					(fill
						(type none)
					)
				)
				(pin passive line
					(at 0 0 0)
					(length 2.54)
					(name "1"
						(effects
							(font
								(size 1.27 1.27)
							)
						)
					)
					(number "1"
						(effects
							(font
								(size 1.27 1.27)
							)
						)
					)
				)
			)
		)
	(symbol "antmicroTestPoints:TP_1mm_SMD"
			(pin_names
				(hide yes)
			)
			(exclude_from_sim no)
			(in_bom no)
			(on_board yes)
			(property "Reference" "TP"
				(at 15.24 -5.08 0)
				(effects
					(font
						(size 1.27 1.27)
						(thickness 0.15)
					)
					(justify left bottom)
				)
			)
			(property "Value" "TP_1mm_SMD"
				(at 15.24 -7.62 0)
				(effects
					(font
						(size 1.27 1.27)
						(thickness 0.15)
					)
					(justify left bottom)
					(hide yes)
				)
			)
			(property "Footprint" "antmicro-footprints:TP_SMD_1mm"
				(at 15.24 -10.16 0)
				(effects
					(font
						(size 1.27 1.27)
						(thickness 0.15)
					)
					(justify left bottom)
					(hide yes)
				)
			)
			(property "Datasheet" ""
				(at 17.78 -12.7 0)
				(effects
					(font
						(size 1.27 1.27)
						(thickness 0.15)
					)
					(justify left bottom)
					(hide yes)
				)
			)
			(property "Description" "Test point 1mm SMD"
				(at 0 0 0)
				(effects
					(font
						(size 1.27 1.27)
					)
					(hide yes)
				)
			)
			(property "MPN" ""
				(at 0 0 0)
				(effects
					(font
						(size 1.27 1.27)
					)
					(hide yes)
				)
			)
			(property "Manufacturer" ""
				(at 0 0 0)
				(effects
					(font
						(size 1.27 1.27)
					)
					(hide yes)
				)
			)
			(property "Author" "Antmicro"
				(at 15.24 -15.24 0)
				(effects
					(font
						(size 1.27 1.27)
						(thickness 0.15)
					)
					(justify left bottom)
					(hide yes)
				)
			)
			(property "License" "Apache-2.0"
				(at 15.24 -17.78 0)
				(effects
					(font
						(size 1.27 1.27)
						(thickness 0.15)
					)
					(justify left bottom)
					(hide yes)
				)
			)
			(property "ki_keywords" "TESTPOINT"
				(at 0 0 0)
				(effects
					(font
						(size 1.27 1.27)
					)
					(hide yes)
				)
			)
			(symbol "TP_1mm_SMD_1_1"
				(circle
					(center 3.175 0)
					(radius 0.635)
					(stroke
						(width 0.254)
						(type default)
					)
					(fill
						(type none)
					)
				)
				(pin passive line
					(at 0 0 0)
					(length 2.54)
					(name "1"
						(effects
							(font
								(size 1.27 1.27)
							)
						)
					)
					(number "1"
						(effects
							(font
								(size 1.27 1.27)
							)
						)
					)
				)
			)
		)
	(symbol "antmicroUSBConnectors:USB-C_GCT_USB4105-GF-A"
			(exclude_from_sim no)
			(in_bom yes)
			(on_board yes)
			(property "Reference" "J"
				(at 38.1 -2.54 0)
				(effects
					(font
						(size 1.27 1.27)
						(thickness 0.15)
					)
					(justify left bottom)
				)
			)
			(property "Value" "USB-C_GCT_USB4105-GF-A"
				(at 38.1 -5.08 0)
				(effects
					(font
						(size 1.27 1.27)
						(thickness 0.15)
					)
					(justify left bottom)
					(hide yes)
				)
			)
			(property "Footprint" "antmicro-footprints:USB-C_Receptacle_GCT_USB4105-GF-A"
				(at 38.1 -7.62 0)
				(effects
					(font
						(size 1.27 1.27)
						(thickness 0.15)
					)
					(justify left bottom)
					(hide yes)
				)
			)
			(property "Datasheet" "https://gct.co/files/drawings/usb4105.pdf"
				(at 38.1 -10.16 0)
				(effects
					(font
						(size 1.27 1.27)
						(thickness 0.15)
					)
					(justify left bottom)
					(hide yes)
				)
			)
			(property "Description" "USB-C (USB TYPE-C) USB 2.0 Receptacle Connector 24 (16+8 Dummy) Position Surface Mount, Right Angle"
				(at 38.1 -22.86 0)
				(effects
					(font
						(size 1.27 1.27)
					)
					(justify left bottom)
					(hide yes)
				)
			)
			(property "Manufacturer" "GCT"
				(at 38.1 -12.7 0)
				(effects
					(font
						(size 1.27 1.27)
						(thickness 0.15)
					)
					(justify left bottom)
					(hide yes)
				)
			)
			(property "MPN" "USB4105-GF-A"
				(at 38.1 -15.24 0)
				(effects
					(font
						(size 1.27 1.27)
						(thickness 0.15)
					)
					(justify left bottom)
				)
			)
			(property "Author" "Antmicro"
				(at 38.1 -17.78 0)
				(effects
					(font
						(size 1.27 1.27)
						(thickness 0.15)
					)
					(justify left bottom)
					(hide yes)
				)
			)
			(property "License" "Apache-2.0"
				(at 38.1 -20.32 0)
				(effects
					(font
						(size 1.27 1.27)
						(thickness 0.15)
					)
					(justify left bottom)
					(hide yes)
				)
			)
			(property "ki_keywords" "USB, CONNECTOR, SMT, HORIZONTAL"
				(at 0 0 0)
				(effects
					(font
						(size 1.27 1.27)
					)
					(hide yes)
				)
			)
			(symbol "USB-C_GCT_USB4105-GF-A_1_1"
				(rectangle
					(start -22.86 2.54)
					(end -3.81 -38.1)
					(stroke
						(width 0.254)
						(type default)
					)
					(fill
						(type background)
					)
				)
				(circle
					(center -20.066 -18.034)
					(radius 0.284)
					(stroke
						(width 0.254)
						(type default)
					)
					(fill
						(type outline)
					)
				)
				(polyline
					(pts
						(xy -19.812 -16.383) (xy -19.177 -15.24) (xy -18.542 -16.383) (xy -19.812 -16.383)
					)
					(stroke
						(width 0.254)
						(type default)
					)
					(fill
						(type outline)
					)
				)
				(polyline
					(pts
						(xy -19.177 -19.558) (xy -18.288 -18.669) (xy -18.288 -18.034)
					)
					(stroke
						(width 0.254)
						(type default)
					)
					(fill
						(type background)
					)
				)
				(polyline
					(pts
						(xy -19.177 -19.939) (xy -20.066 -19.05) (xy -20.066 -18.415)
					)
					(stroke
						(width 0.254)
						(type default)
					)
					(fill
						(type background)
					)
				)
				(polyline
					(pts
						(xy -19.177 -20.701) (xy -19.177 -16.383)
					)
					(stroke
						(width 0.254)
						(type default)
					)
					(fill
						(type background)
					)
				)
				(circle
					(center -19.177 -20.828)
					(radius 0.5236)
					(stroke
						(width 0.254)
						(type default)
					)
					(fill
						(type outline)
					)
				)
				(rectangle
					(start -18.669 -18.034)
					(end -17.907 -17.272)
					(stroke
						(width 0.254)
						(type default)
					)
					(fill
						(type outline)
					)
				)
				(polyline
					(pts
						(xy -16.51 -21.59) (xy -16.51 -13.97)
					)
					(stroke
						(width 0.254)
						(type default)
					)
					(fill
						(type background)
					)
				)
				(rectangle
					(start -15.24 -21.59)
					(end -13.97 -13.97)
					(stroke
						(width 0.254)
						(type default)
					)
					(fill
						(type outline)
					)
				)
				(arc
					(start -15.24 -13.97)
					(mid -14.605 -13.3377)
					(end -13.97 -13.97)
					(stroke
						(width 0.254)
						(type default)
					)
					(fill
						(type outline)
					)
				)
				(arc
					(start -15.24 -13.97)
					(mid -14.605 -13.3377)
					(end -13.97 -13.97)
					(stroke
						(width 0.254)
						(type default)
					)
					(fill
						(type background)
					)
				)
				(arc
					(start -16.51 -13.97)
					(mid -14.605 -12.0733)
					(end -12.7 -13.97)
					(stroke
						(width 0.254)
						(type default)
					)
					(fill
						(type background)
					)
				)
				(arc
					(start -12.7 -21.59)
					(mid -14.605 -23.4867)
					(end -16.51 -21.59)
					(stroke
						(width 0.254)
						(type default)
					)
					(fill
						(type background)
					)
				)
				(arc
					(start -13.97 -21.59)
					(mid -14.605 -22.2223)
					(end -15.24 -21.59)
					(stroke
						(width 0.254)
						(type default)
					)
					(fill
						(type outline)
					)
				)
				(arc
					(start -13.97 -21.59)
					(mid -14.605 -22.2223)
					(end -15.24 -21.59)
					(stroke
						(width 0.254)
						(type default)
					)
					(fill
						(type background)
					)
				)
				(polyline
					(pts
						(xy -12.7 -13.97) (xy -12.7 -21.59)
					)
					(stroke
						(width 0.254)
						(type default)
					)
					(fill
						(type background)
					)
				)
				(pin power_in line
					(at 0 0 180)
					(length 3.81)
					(name "VBUS"
						(effects
							(font
								(size 1.27 1.27)
							)
						)
					)
					(number "A4"
						(effects
							(font
								(size 1.27 1.27)
							)
						)
					)
				)
				(pin passive line
					(at 0 0 180)
					(length 3.81)
					(hide yes)
					(name "VBUS"
						(effects
							(font
								(size 1.27 1.27)
							)
						)
					)
					(number "A9"
						(effects
							(font
								(size 1.27 1.27)
							)
						)
					)
				)
				(pin passive line
					(at 0 0 180)
					(length 3.81)
					(hide yes)
					(name "VBUS"
						(effects
							(font
								(size 1.27 1.27)
							)
						)
					)
					(number "B4"
						(effects
							(font
								(size 1.27 1.27)
							)
						)
					)
				)
				(pin passive line
					(at 0 0 180)
					(length 3.81)
					(hide yes)
					(name "VBUS"
						(effects
							(font
								(size 1.27 1.27)
							)
						)
					)
					(number "B9"
						(effects
							(font
								(size 1.27 1.27)
							)
						)
					)
				)
				(pin bidirectional line
					(at 0 -5.08 180)
					(length 3.81)
					(name "CC_{1}"
						(effects
							(font
								(size 1.27 1.27)
							)
						)
					)
					(number "A5"
						(effects
							(font
								(size 1.27 1.27)
							)
						)
					)
				)
				(pin bidirectional line
					(at 0 -7.62 180)
					(length 3.81)
					(name "CC_{2}"
						(effects
							(font
								(size 1.27 1.27)
							)
						)
					)
					(number "B5"
						(effects
							(font
								(size 1.27 1.27)
							)
						)
					)
				)
				(pin bidirectional line
					(at 0 -12.7 180)
					(length 3.81)
					(name "D_{A}+"
						(effects
							(font
								(size 1.27 1.27)
							)
						)
					)
					(number "A6"
						(effects
							(font
								(size 1.27 1.27)
							)
						)
					)
				)
				(pin bidirectional line
					(at 0 -15.24 180)
					(length 3.81)
					(name "D_{A}-"
						(effects
							(font
								(size 1.27 1.27)
							)
						)
					)
					(number "A7"
						(effects
							(font
								(size 1.27 1.27)
							)
						)
					)
				)
				(pin bidirectional line
					(at 0 -17.78 180)
					(length 3.81)
					(name "D_{B}+"
						(effects
							(font
								(size 1.27 1.27)
							)
						)
					)
					(number "B6"
						(effects
							(font
								(size 1.27 1.27)
							)
						)
					)
				)
				(pin bidirectional line
					(at 0 -20.32 180)
					(length 3.81)
					(name "D_{B}-"
						(effects
							(font
								(size 1.27 1.27)
							)
						)
					)
					(number "B7"
						(effects
							(font
								(size 1.27 1.27)
							)
						)
					)
				)
				(pin bidirectional line
					(at 0 -25.4 180)
					(length 3.81)
					(name "SBU_{1}"
						(effects
							(font
								(size 1.27 1.27)
							)
						)
					)
					(number "A8"
						(effects
							(font
								(size 1.27 1.27)
							)
						)
					)
				)
				(pin bidirectional line
					(at 0 -27.94 180)
					(length 3.81)
					(name "SBU_{2}"
						(effects
							(font
								(size 1.27 1.27)
							)
						)
					)
					(number "B8"
						(effects
							(font
								(size 1.27 1.27)
							)
						)
					)
				)
				(pin power_in line
					(at 0 -33.02 180)
					(length 3.81)
					(name "GND"
						(effects
							(font
								(size 1.27 1.27)
							)
						)
					)
					(number "A1"
						(effects
							(font
								(size 1.27 1.27)
							)
						)
					)
				)
				(pin passive line
					(at 0 -33.02 180)
					(length 3.81)
					(hide yes)
					(name "GND"
						(effects
							(font
								(size 1.27 1.27)
							)
						)
					)
					(number "A12"
						(effects
							(font
								(size 1.27 1.27)
							)
						)
					)
				)
				(pin passive line
					(at 0 -33.02 180)
					(length 3.81)
					(hide yes)
					(name "GND"
						(effects
							(font
								(size 1.27 1.27)
							)
						)
					)
					(number "B1"
						(effects
							(font
								(size 1.27 1.27)
							)
						)
					)
				)
				(pin passive line
					(at 0 -33.02 180)
					(length 3.81)
					(hide yes)
					(name "GND"
						(effects
							(font
								(size 1.27 1.27)
							)
						)
					)
					(number "B12"
						(effects
							(font
								(size 1.27 1.27)
							)
						)
					)
				)
				(pin passive line
					(at 0 -35.56 180)
					(length 3.81)
					(name "SH"
						(effects
							(font
								(size 1.27 1.27)
							)
						)
					)
					(number "SH"
						(effects
							(font
								(size 1.27 1.27)
							)
						)
					)
				)
			)
		)
	(symbol "antmicroWire2BoardConnectors:JST_SH_1x4_SM04B-SRSS-TB-LF-SN"
			(exclude_from_sim no)
			(in_bom yes)
			(on_board yes)
			(property "Reference" "J"
				(at 26.67 -2.54 0)
				(effects
					(font
						(size 1.27 1.27)
						(thickness 0.15)
					)
					(justify left bottom)
				)
			)
			(property "Value" "JST_SH_1x4_SM04B-SRSS-TB-LF-SN"
				(at 26.67 -7.62 0)
				(effects
					(font
						(size 1.27 1.27)
						(thickness 0.15)
					)
					(justify left bottom)
					(hide yes)
				)
			)
			(property "Footprint" "antmicro-footprints:Conn_JST_SH_1x4_SM04B-SRSS-TB-LF-SN"
				(at 26.67 -10.16 0)
				(effects
					(font
						(size 1.27 1.27)
						(thickness 0.15)
					)
					(justify left bottom)
					(hide yes)
				)
			)
			(property "Datasheet" "https://www.jst-mfg.com/product/pdf/eng/eSH.pdf"
				(at 26.67 -12.7 0)
				(effects
					(font
						(size 1.27 1.27)
						(thickness 0.15)
					)
					(justify left bottom)
					(hide yes)
				)
			)
			(property "Description" "Pin Header, Right Angle, Wire-to-Board, 1 mm, 1 Rows, 4 Contacts, Surface Mount Right Angle, SH"
				(at 0 0 0)
				(effects
					(font
						(size 1.27 1.27)
					)
					(hide yes)
				)
			)
			(property "MPN" "SM04B-SRSS-TB(LF)(SN)"
				(at 26.67 -5.08 0)
				(effects
					(font
						(size 1.27 1.27)
						(thickness 0.15)
					)
					(justify left bottom)
				)
			)
			(property "Manufacturer" "JST Automotive Connectors"
				(at 26.67 -15.24 0)
				(effects
					(font
						(size 1.27 1.27)
						(thickness 0.15)
					)
					(justify left bottom)
					(hide yes)
				)
			)
			(property "Author" "Antmicro"
				(at 26.67 -17.78 0)
				(effects
					(font
						(size 1.27 1.27)
						(thickness 0.15)
					)
					(justify left bottom)
					(hide yes)
				)
			)
			(property "License" "Apache-2.0"
				(at 26.67 -20.32 0)
				(effects
					(font
						(size 1.27 1.27)
						(thickness 0.15)
					)
					(justify left bottom)
					(hide yes)
				)
			)
			(property "ki_keywords" "VERTICAL, SMT, WIRE-BOARD, CONNECTOR, MALE, HEADER"
				(at 0 0 0)
				(effects
					(font
						(size 1.27 1.27)
					)
					(hide yes)
				)
			)
			(symbol "JST_SH_1x4_SM04B-SRSS-TB-LF-SN_1_1"
				(rectangle
					(start 2.54 2.54)
					(end 5.08 -12.7)
					(stroke
						(width 0.254)
						(type default)
					)
					(fill
						(type background)
					)
				)
				(rectangle
					(start 2.54 0.127)
					(end 3.81 -0.127)
					(stroke
						(width 0.254)
						(type default)
					)
					(fill
						(type background)
					)
				)
				(rectangle
					(start 2.54 -2.413)
					(end 3.81 -2.667)
					(stroke
						(width 0.254)
						(type default)
					)
					(fill
						(type background)
					)
				)
				(rectangle
					(start 2.54 -4.953)
					(end 3.81 -5.207)
					(stroke
						(width 0.254)
						(type default)
					)
					(fill
						(type background)
					)
				)
				(rectangle
					(start 2.54 -7.493)
					(end 3.81 -7.747)
					(stroke
						(width 0.254)
						(type default)
					)
					(fill
						(type background)
					)
				)
				(rectangle
					(start 2.54 -10.033)
					(end 3.81 -10.287)
					(stroke
						(width 0.254)
						(type default)
					)
					(fill
						(type background)
					)
				)
				(pin passive line
					(at 0 0 0)
					(length 2.54)
					(name "~"
						(effects
							(font
								(size 1.27 1.27)
							)
						)
					)
					(number "1"
						(effects
							(font
								(size 1.27 1.27)
							)
						)
					)
				)
				(pin passive line
					(at 0 -2.54 0)
					(length 2.54)
					(name "~"
						(effects
							(font
								(size 1.27 1.27)
							)
						)
					)
					(number "2"
						(effects
							(font
								(size 1.27 1.27)
							)
						)
					)
				)
				(pin passive line
					(at 0 -5.08 0)
					(length 2.54)
					(name "~"
						(effects
							(font
								(size 1.27 1.27)
							)
						)
					)
					(number "3"
						(effects
							(font
								(size 1.27 1.27)
							)
						)
					)
				)
				(pin passive line
					(at 0 -7.62 0)
					(length 2.54)
					(name "~"
						(effects
							(font
								(size 1.27 1.27)
							)
						)
					)
					(number "4"
						(effects
							(font
								(size 1.27 1.27)
							)
						)
					)
				)
				(pin passive line
					(at 0 -10.16 0)
					(length 2.54)
					(name "~"
						(effects
							(font
								(size 1.27 1.27)
							)
						)
					)
					(number "MP"
						(effects
							(font
								(size 1.27 1.27)
							)
						)
					)
				)
			)
		)
	(symbol "antmicropower:+3V3"
			(power)
			(pin_numbers
				(hide yes)
			)
			(pin_names
				(hide yes)
			)
			(exclude_from_sim no)
			(in_bom yes)
			(on_board yes)
			(property "Reference" "#PWR"
				(at 15.24 0 0)
				(effects
					(font
						(size 1.27 1.27)
						(thickness 0.15)
					)
					(justify left bottom)
					(hide yes)
				)
			)
			(property "Value" "+3V3"
				(at -3.175 2.54 0)
				(effects
					(font
						(size 1.27 1.27)
						(thickness 0.15)
					)
					(justify left bottom)
				)
			)
			(property "Footprint" ""
				(at 15.24 -7.62 0)
				(effects
					(font
						(size 1.27 1.27)
						(thickness 0.15)
					)
					(justify left bottom)
					(hide yes)
				)
			)
			(property "Datasheet" ""
				(at 15.24 -10.16 0)
				(effects
					(font
						(size 1.27 1.27)
						(thickness 0.15)
					)
					(justify left bottom)
					(hide yes)
				)
			)
			(property "Description" ""
				(at 0 0 0)
				(effects
					(font
						(size 1.27 1.27)
					)
					(hide yes)
				)
			)
			(property "Author" "Antmicro"
				(at 15.24 -2.54 0)
				(effects
					(font
						(size 1.27 1.27)
						(thickness 0.15)
					)
					(justify left bottom)
					(hide yes)
				)
			)
			(property "License" "Apache-2.0"
				(at 15.24 -5.08 0)
				(effects
					(font
						(size 1.27 1.27)
						(thickness 0.15)
					)
					(justify left bottom)
					(hide yes)
				)
			)
			(symbol "+3V3_0_1"
				(polyline
					(pts
						(xy 0 2.54) (xy -0.762 1.27)
					)
					(stroke
						(width 0)
						(type default)
					)
					(fill
						(type none)
					)
				)
				(polyline
					(pts
						(xy 0 2.54) (xy 0.762 1.27)
					)
					(stroke
						(width 0)
						(type default)
					)
					(fill
						(type none)
					)
				)
				(polyline
					(pts
						(xy 0 0) (xy 0 2.54)
					)
					(stroke
						(width 0)
						(type default)
					)
					(fill
						(type none)
					)
				)
			)
			(symbol "+3V3_1_1"
				(pin power_in line
					(at 0 0 90)
					(length 0)
					(hide yes)
					(name "+3V3"
						(effects
							(font
								(size 1.27 1.27)
							)
						)
					)
					(number "1"
						(effects
							(font
								(size 1.27 1.27)
							)
						)
					)
				)
			)
		)
	(symbol "antmicropower:+5V"
			(power)
			(pin_numbers
				(hide yes)
			)
			(pin_names
				(hide yes)
			)
			(exclude_from_sim no)
			(in_bom yes)
			(on_board yes)
			(property "Reference" "#PWR"
				(at 15.24 -2.54 0)
				(effects
					(font
						(size 1.27 1.27)
						(thickness 0.15)
					)
					(justify left bottom)
					(hide yes)
				)
			)
			(property "Value" "+5V"
				(at 15.24 -5.08 0)
				(effects
					(font
						(size 1.27 1.27)
						(thickness 0.15)
					)
					(justify left bottom)
				)
			)
			(property "Footprint" ""
				(at 15.24 -7.62 0)
				(effects
					(font
						(size 1.27 1.27)
						(thickness 0.15)
					)
					(justify left bottom)
					(hide yes)
				)
			)
			(property "Datasheet" ""
				(at 15.24 -10.16 0)
				(effects
					(font
						(size 1.27 1.27)
						(thickness 0.15)
					)
					(justify left bottom)
					(hide yes)
				)
			)
			(property "Description" ""
				(at 0 0 0)
				(effects
					(font
						(size 1.27 1.27)
					)
					(hide yes)
				)
			)
			(property "Author" "Antmicro"
				(at 15.24 -7.62 0)
				(effects
					(font
						(size 1.27 1.27)
						(thickness 0.15)
					)
					(justify left bottom)
					(hide yes)
				)
			)
			(property "License" "Apache-2.0"
				(at 15.24 -10.16 0)
				(effects
					(font
						(size 1.27 1.27)
						(thickness 0.15)
					)
					(justify left bottom)
					(hide yes)
				)
			)
			(symbol "+5V_1_1"
				(polyline
					(pts
						(xy -0.762 1.27) (xy 0 2.54)
					)
					(stroke
						(width 0)
						(type default)
					)
					(fill
						(type background)
					)
				)
				(polyline
					(pts
						(xy 0 2.54) (xy 0.762 1.27)
					)
					(stroke
						(width 0)
						(type default)
					)
					(fill
						(type background)
					)
				)
				(polyline
					(pts
						(xy 0 0) (xy 0 2.54)
					)
					(stroke
						(width 0)
						(type default)
					)
					(fill
						(type background)
					)
				)
				(pin power_in line
					(at 0 0 90)
					(length 0)
					(name "+5V"
						(effects
							(font
								(size 1.27 1.27)
							)
						)
					)
					(number "1"
						(effects
							(font
								(size 1.27 1.27)
							)
						)
					)
				)
			)
		)
	(symbol "antmicropower:GND"
			(power)
			(pin_numbers
				(hide yes)
			)
			(pin_names
				(hide yes)
			)
			(exclude_from_sim no)
			(in_bom yes)
			(on_board yes)
			(property "Reference" "#PWR"
				(at 8.89 -2.54 0)
				(effects
					(font
						(size 1.27 1.27)
						(thickness 0.15)
					)
					(justify left bottom)
					(hide yes)
				)
			)
			(property "Value" "GND"
				(at 8.89 -5.08 0)
				(effects
					(font
						(size 1.27 1.27)
						(thickness 0.15)
					)
					(justify left bottom)
				)
			)
			(property "Footprint" ""
				(at 8.89 -7.62 0)
				(effects
					(font
						(size 1.27 1.27)
						(thickness 0.15)
					)
					(justify left bottom)
					(hide yes)
				)
			)
			(property "Datasheet" ""
				(at 8.89 -12.7 0)
				(effects
					(font
						(size 1.27 1.27)
						(thickness 0.15)
					)
					(justify left bottom)
					(hide yes)
				)
			)
			(property "Description" ""
				(at 0 0 0)
				(effects
					(font
						(size 1.27 1.27)
					)
					(hide yes)
				)
			)
			(property "Author" "Antmicro"
				(at 8.89 -7.62 0)
				(effects
					(font
						(size 1.27 1.27)
						(thickness 0.15)
					)
					(justify left bottom)
					(hide yes)
				)
			)
			(property "License" "Apache-2.0"
				(at 8.89 -10.16 0)
				(effects
					(font
						(size 1.27 1.27)
						(thickness 0.15)
					)
					(justify left bottom)
					(hide yes)
				)
			)
			(symbol "GND_1_1"
				(polyline
					(pts
						(xy 0 0) (xy 0 -1.27) (xy 1.27 -1.27) (xy 0 -2.54) (xy -1.27 -1.27) (xy 0 -1.27)
					)
					(stroke
						(width 0)
						(type default)
					)
					(fill
						(type none)
					)
				)
				(pin power_in line
					(at 0 0 270)
					(length 0)
					(name "GND"
						(effects
							(font
								(size 1.27 1.27)
							)
						)
					)
					(number "1"
						(effects
							(font
								(size 1.27 1.27)
							)
						)
					)
				)
			)
		)
	(symbol "antmicropower:GNDREF"
			(power)
			(pin_names
				(offset 0)
			)
			(exclude_from_sim no)
			(in_bom yes)
			(on_board yes)
			(property "Reference" "#PWR"
				(at 0 -6.35 0)
				(effects
					(font
						(size 1.27 1.27)
					)
					(hide yes)
				)
			)
			(property "Value" "GNDREF"
				(at 0 -3.81 0)
				(effects
					(font
						(size 1.27 1.27)
					)
				)
			)
			(property "Footprint" ""
				(at 0 0 0)
				(effects
					(font
						(size 1.27 1.27)
					)
					(hide yes)
				)
			)
			(property "Datasheet" ""
				(at 0 0 0)
				(effects
					(font
						(size 1.27 1.27)
					)
					(hide yes)
				)
			)
			(property "Description" ""
				(at 0 0 0)
				(effects
					(font
						(size 1.27 1.27)
					)
					(hide yes)
				)
			)
			(symbol "GNDREF_0_1"
				(polyline
					(pts
						(xy -0.635 -1.905) (xy 0.635 -1.905)
					)
					(stroke
						(width 0)
						(type default)
					)
					(fill
						(type none)
					)
				)
				(polyline
					(pts
						(xy -0.127 -2.54) (xy 0.127 -2.54)
					)
					(stroke
						(width 0)
						(type default)
					)
					(fill
						(type none)
					)
				)
				(polyline
					(pts
						(xy 0 -1.27) (xy 0 0)
					)
					(stroke
						(width 0)
						(type default)
					)
					(fill
						(type none)
					)
				)
				(polyline
					(pts
						(xy 1.27 -1.27) (xy -1.27 -1.27)
					)
					(stroke
						(width 0)
						(type default)
					)
					(fill
						(type none)
					)
				)
			)
			(symbol "GNDREF_1_1"
				(pin power_in line
					(at 0 0 270)
					(length 0)
					(hide yes)
					(name "GNDREF"
						(effects
							(font
								(size 1.27 1.27)
							)
						)
					)
					(number "1"
						(effects
							(font
								(size 1.27 1.27)
							)
						)
					)
				)
			)
		)
	(symbol "antmicropower:PWR_FLAG"
			(power)
			(pin_numbers
				(hide yes)
			)
			(pin_names
				(offset 0)
				(hide yes)
			)
			(exclude_from_sim no)
			(in_bom yes)
			(on_board yes)
			(property "Reference" "#FLG"
				(at 0 1.905 0)
				(effects
					(font
						(size 1.27 1.27)
					)
					(hide yes)
				)
			)
			(property "Value" "PWR_FLAG"
				(at 0 3.81 0)
				(effects
					(font
						(size 1.27 1.27)
					)
				)
			)
			(property "Footprint" ""
				(at 0 0 0)
				(effects
					(font
						(size 1.27 1.27)
					)
					(hide yes)
				)
			)
			(property "Datasheet" ""
				(at 0 0 0)
				(effects
					(font
						(size 1.27 1.27)
					)
					(hide yes)
				)
			)
			(property "Description" ""
				(at 0 0 0)
				(effects
					(font
						(size 1.27 1.27)
					)
					(hide yes)
				)
			)
			(symbol "PWR_FLAG_0_0"
				(pin power_out line
					(at 0 0 90)
					(length 0)
					(name "pwr"
						(effects
							(font
								(size 1.27 1.27)
							)
						)
					)
					(number "1"
						(effects
							(font
								(size 1.27 1.27)
							)
						)
					)
				)
			)
			(symbol "PWR_FLAG_0_1"
				(polyline
					(pts
						(xy 0 0) (xy 0 1.27) (xy -1.016 1.905) (xy 0 2.54) (xy 1.016 1.905) (xy 0 1.27)
					)
					(stroke
						(width 0)
						(type default)
					)
					(fill
						(type none)
					)
				)
			)
		)
)
